FILE_TYPE = MACRO_DRAWING;
SET COLOR_WIRE YELLOW;
SET COLOR_PROP MONO;
SET COLOR_DOT WHITE;
SET COLOR_ARC YELLOW;
SET COLOR_BODY GREEN;
SET COLOR_NOTE MONO;
SET PROP_DISPLAY VALUE;
SET PAGE_NUMBER P210;
FORCEADD OFFPAGE..4
(-1700 4625);
FORCEPROP 2 LAST $XR0 206 
J 0
(-1514 4625);
DISPLAY 0.638298 (-1514 4625);
PAINT MONO (-1514 4625);
FORCEPROP 2 LAST ROOM PVSA_CPU1_PWR_VR
J 0
(-2100 4700);
DISPLAY 1.936170 (-2100 4700);
PAINT ORANGE (-2100 4700);
DISPLAY INVISIBLE (-2100 4700);
FORCEPROP 2 LAST CDS_LIB mstr_standard
J 0
(-1700 4625);
PAINT ORANGE (-1700 4625);
DISPLAY INVISIBLE (-1700 4625);
FORCEPROP 2 LAST PATH I1
J 0
(-1345 4675);
DISPLAY 1.021277 (-1345 4675);
PAINT ORANGE (-1345 4675);
DISPLAY INVISIBLE (-1345 4675);
FORCEPROP 2 LAST BOM_COST PROC_VRD_VCCIN_CPU0
J 0
(-1500 4675);
DISPLAY 1.446809 (-1500 4675);
PAINT MONO (-1500 4675);
DISPLAY INVISIBLE (-1500 4675);
FORCEPROP 1 LAST OFFPAGE TRUE
J 0
(-1375 4500);
DISPLAY 0.872340 (-1375 4500);
PAINT GREEN (-1375 4500);
DISPLAY INVISIBLE (-1375 4500);
FORCEPROP 1 LAST COMMENT_BODY TRUE
J 0
(-1725 4525);
DISPLAY 0.872340 (-1725 4525);
PAINT GREEN (-1725 4525);
DISPLAY INVISIBLE (-1725 4525);
FORCEADD CAPP..1
(-1350 1450);
FORCEPROP 1 LAST LOCATION C9N11
J 0
(-1300 1550);
DISPLAY 0.617021 (-1300 1550);
PAINT AQUA (-1300 1550);
FORCEPROP 1 LAST VALUE 470UF
J 0
(-1300 1500);
DISPLAY 0.617021 (-1300 1500);
PAINT SKYBLUE (-1300 1500);
FORCEPROP 1 LAST TOLERANCE 20%
J 0
(-1300 1450);
DISPLAY 0.617021 (-1300 1450);
PAINT SKYBLUE (-1300 1450);
FORCEPROP 1 LASTPIN (-1350 1550) $PN 1
J 0
(-1340 1535);
DISPLAY 0.617021 (-1340 1535);
PAINT ORANGE (-1340 1535);
FORCEPROP 1 LASTPIN (-1350 1350) $PN 2
J 0
(-1340 1335);
DISPLAY 0.617021 (-1340 1335);
PAINT ORANGE (-1340 1335);
FORCEPROP 1 LAST PACK_TYPE 3018
J 0
(-1300 1300);
DISPLAY 0.617021 (-1300 1300);
PAINT SKYBLUE (-1300 1300);
FORCEPROP 1 LAST PART_NUMBER 699013-049
J 0
(-1300 1250);
DISPLAY 0.617021 (-1300 1250);
PAINT BLUE (-1300 1250);
FORCEPROP 1 LAST MATERIAL ALUM
J 0
(-1300 1350);
DISPLAY 0.617021 (-1300 1350);
PAINT SKYBLUE (-1300 1350);
FORCEPROP 1 LAST VOLTAGE 2.5V
J 0
(-1300 1400);
DISPLAY 0.638298 (-1300 1400);
PAINT SKYBLUE (-1300 1400);
FORCEPROP 0 LAST GROUP PWR_BULK_CAP
J 0
(-1296 1206);
DISPLAY 0.638298 (-1296 1206);
PAINT BROWN (-1296 1206);
DISPLAY BOTH (-1296 1206);
FORCEPROP 2 LAST SEC 1
J 0
(-1300 1650);
PAINT MONO (-1300 1650);
DISPLAY INVISIBLE (-1300 1650);
FORCEPROP 2 LAST SEC_TYPE 3018
J 0
(-1295 1670);
DISPLAY 1.021277 (-1295 1670);
PAINT ORANGE (-1295 1670);
DISPLAY INVISIBLE (-1295 1670);
FORCEPROP 2 LAST BOM_COST PROC_VRD_VCCIN_CPU0
J 0
(-1300 1600);
PAINT MONO (-1300 1600);
DISPLAY INVISIBLE (-1300 1600);
FORCEPROP 1 LAST PATH I12
J 0
(-1300 1600);
DISPLAY 0.978723 (-1300 1600);
PAINT ORANGE (-1300 1600);
DISPLAY INVISIBLE (-1300 1600);
FORCEPROP 2 LAST ROOM PVSA_CPU1_DECAP_VR
J 0
(-1300 1575);
PAINT MONO (-1300 1575);
DISPLAY INVISIBLE (-1300 1575);
FORCEPROP 2 LAST CDS_LOCATION C9N11
J 0
(-1300 1550);
DISPLAY 0.617021 (-1300 1550);
PAINT AQUA (-1300 1550);
DISPLAY INVISIBLE (-1300 1550);
FORCEPROP 2 LAST CDS_LIB mstr_discrete
J 0
(-1350 1450);
PAINT ORANGE (-1350 1450);
DISPLAY INVISIBLE (-1350 1450);
FORCEADD GND..1
(-1900 1075);
FORCEPROP 3 LASTPIN (-1900 1125) SIG_NAME GND\g
J 0
(-1890 1135);
DISPLAY 0.659574 (-1890 1135);
PAINT MONO (-1890 1135);
DISPLAY INVISIBLE (-1890 1135);
FORCEPROP 2 LAST BOM_COST PROC_VRD_VCCIN_CPU0
J 0
(-2275 1150);
DISPLAY 1.446809 (-2275 1150);
PAINT MONO (-2275 1150);
DISPLAY INVISIBLE (-2275 1150);
FORCEPROP 2 LAST ROOM PVSA_CPU1_DECAP_VR
J 0
(-2450 1150);
DISPLAY 1.936170 (-2450 1150);
PAINT ORANGE (-2450 1150);
DISPLAY INVISIBLE (-2450 1150);
FORCEPROP 1 LAST VOLTAGE 0
J 0
(-1900 1075);
PAINT SKYBLUE (-1900 1075);
DISPLAY INVISIBLE (-1900 1075);
FORCEPROP 1 LAST SIZE 1B
J 0
(-1825 1025);
DISPLAY 1.723404 (-1825 1025);
PAINT GREEN (-1825 1025);
DISPLAY INVISIBLE (-1825 1025);
FORCEPROP 2 LAST CDS_LIB mstr_symbols
J 0
(-1900 1075);
PAINT ORANGE (-1900 1075);
DISPLAY INVISIBLE (-1900 1075);
FORCEPROP 1 LAST PATH I13
J 0
(-1825 1075);
DISPLAY 0.872340 (-1825 1075);
PAINT AQUA (-1825 1075);
DISPLAY INVISIBLE (-1825 1075);
FORCEPROP 1 LAST BODY_TYPE PLUMBING
J 0
(-1945 1032);
DISPLAY 0.340426 (-1945 1032);
PAINT GREEN (-1945 1032);
DISPLAY INVISIBLE (-1945 1032);
FORCEPROP 1 LAST HDL_POWER GND
J 0
(-1900 1225);
DISPLAY 1.723404 (-1900 1225);
PAINT GREEN (-1900 1225);
DISPLAY INVISIBLE (-1900 1225);
FORCEADD CAPP..1
R 2
(-1900 1450);
FORCEPROP 1 LASTPIN (-1900 1350) $PN 2
J 2
(-1910 1335);
DISPLAY 0.617021 (-1910 1335);
PAINT GREEN (-1910 1335);
FORCEPROP 1 LASTPIN (-1900 1550) $PN 1
J 2
(-1910 1535);
DISPLAY 0.617021 (-1910 1535);
PAINT GREEN (-1910 1535);
FORCEPROP 1 LAST TOLERANCE 20%
J 0
(-1850 1450);
DISPLAY 0.617021 (-1850 1450);
PAINT SKYBLUE (-1850 1450);
FORCEPROP 1 LAST VOLTAGE 2.5V
J 0
(-1850 1400);
DISPLAY 0.617021 (-1850 1400);
PAINT SKYBLUE (-1850 1400);
FORCEPROP 1 LAST MATERIAL ALUM
J 0
(-1850 1350);
DISPLAY 0.617021 (-1850 1350);
PAINT SKYBLUE (-1850 1350);
FORCEPROP 1 LAST PACK_TYPE 3018
J 0
(-1850 1300);
DISPLAY 0.617021 (-1850 1300);
PAINT SKYBLUE (-1850 1300);
FORCEPROP 1 LAST LOCATION C9N20
J 0
(-1850 1550);
DISPLAY 0.617021 (-1850 1550);
PAINT AQUA (-1850 1550);
FORCEPROP 1 LAST VALUE 470UF
J 0
(-1850 1500);
DISPLAY 0.617021 (-1850 1500);
PAINT SKYBLUE (-1850 1500);
FORCEPROP 1 LAST PART_NUMBER 699013-049
J 0
(-1850 1250);
DISPLAY 0.617021 (-1850 1250);
PAINT BLUE (-1850 1250);
FORCEPROP 0 LAST GROUP PWR_BULK_CAP
J 0
(-1846 1206);
DISPLAY 0.638298 (-1846 1206);
PAINT BROWN (-1846 1206);
DISPLAY BOTH (-1846 1206);
FORCEPROP 2 LAST CDS_LIB mstr_discrete
J 2
(-1900 1450);
PAINT ORANGE (-1900 1450);
DISPLAY INVISIBLE (-1900 1450);
FORCEPROP 2 LAST CDS_LOCATION C9N20
J 2
(-1950 1550);
DISPLAY 0.617021 (-1950 1550);
PAINT AQUA (-1950 1550);
DISPLAY INVISIBLE (-1950 1550);
FORCEPROP 2 LAST SEC 1
J 0
(-1940 1665);
DISPLAY 0.680851 (-1940 1665);
PAINT MONO (-1940 1665);
DISPLAY INVISIBLE (-1940 1665);
FORCEPROP 2 LAST SEC_TYPE 3018
J 0
(-1940 1665);
DISPLAY 1.021277 (-1940 1665);
PAINT ORANGE (-1940 1665);
DISPLAY INVISIBLE (-1940 1665);
FORCEPROP 2 LAST BOM_COST PROC_VRD_VCCIN_CPU0
J 0
(-1950 1600);
PAINT MONO (-1950 1600);
DISPLAY INVISIBLE (-1950 1600);
FORCEPROP 1 LAST PATH I14
J 0
(-1950 1600);
DISPLAY 0.978723 (-1950 1600);
PAINT ORANGE (-1950 1600);
DISPLAY INVISIBLE (-1950 1600);
FORCEPROP 2 LAST ROOM PVSA_CPU1_DECAP_VR
J 0
(-1950 1575);
PAINT MONO (-1950 1575);
DISPLAY INVISIBLE (-1950 1575);
FORCEADD GND..1
(-3100 2900);
FORCEPROP 3 LASTPIN (-3100 2950) SIG_NAME GND\g
J 0
(-3090 2960);
DISPLAY 0.659574 (-3090 2960);
PAINT MONO (-3090 2960);
DISPLAY INVISIBLE (-3090 2960);
FORCEPROP 2 LAST ROOM PVSA_CPU1_PWR_VR
J 0
(-3650 2975);
DISPLAY 1.936170 (-3650 2975);
PAINT ORANGE (-3650 2975);
DISPLAY INVISIBLE (-3650 2975);
FORCEPROP 2 LAST BOM_COST PROC_VRD_VCCIN_CPU0
J 0
(-3475 2975);
DISPLAY 1.446809 (-3475 2975);
PAINT MONO (-3475 2975);
DISPLAY INVISIBLE (-3475 2975);
FORCEPROP 2 LAST CDS_LIB mstr_symbols
J 0
(-3100 2900);
PAINT ORANGE (-3100 2900);
DISPLAY INVISIBLE (-3100 2900);
FORCEPROP 1 LAST VOLTAGE 0
J 0
(-3100 2900);
PAINT SKYBLUE (-3100 2900);
DISPLAY INVISIBLE (-3100 2900);
FORCEPROP 1 LAST PATH I15
J 0
(-3025 2900);
DISPLAY 0.872340 (-3025 2900);
PAINT AQUA (-3025 2900);
DISPLAY INVISIBLE (-3025 2900);
FORCEPROP 1 LAST SIZE 1B
J 0
(-3025 2850);
DISPLAY 1.723404 (-3025 2850);
PAINT GREEN (-3025 2850);
DISPLAY INVISIBLE (-3025 2850);
FORCEPROP 1 LAST BODY_TYPE PLUMBING
J 0
(-3145 2857);
DISPLAY 0.340426 (-3145 2857);
PAINT GREEN (-3145 2857);
DISPLAY INVISIBLE (-3145 2857);
FORCEPROP 1 LAST HDL_POWER GND
J 0
(-3100 3050);
DISPLAY 1.723404 (-3100 3050);
PAINT GREEN (-3100 3050);
DISPLAY INVISIBLE (-3100 3050);
FORCEADD OFFPAGE..2
(-3950 1925);
FORCEPROP 2 LAST $XR0 73 
J 0
(-3761 1925);
DISPLAY 0.638298 (-3761 1925);
PAINT MONO (-3761 1925);
FORCEPROP 2 LAST ROOM PVSA_CPU1_VSENSE_VR
J 0
(-4350 2000);
PAINT ORANGE (-4350 2000);
DISPLAY INVISIBLE (-4350 2000);
FORCEPROP 2 LAST CDS_LIB mstr_standard
J 0
(-3950 1925);
PAINT ORANGE (-3950 1925);
DISPLAY INVISIBLE (-3950 1925);
FORCEPROP 2 LAST PATH I17
J 0
(-3785 1985);
DISPLAY 1.021277 (-3785 1985);
PAINT ORANGE (-3785 1985);
DISPLAY INVISIBLE (-3785 1985);
FORCEPROP 2 LAST BOM_COST PROC_VRD_VCCIN_CPU0
J 0
(-3625 1975);
PAINT MONO (-3625 1975);
DISPLAY INVISIBLE (-3625 1975);
FORCEPROP 1 LAST OFFPAGE TRUE
J 0
(-3625 1800);
DISPLAY 0.893617 (-3625 1800);
PAINT GREEN (-3625 1800);
DISPLAY INVISIBLE (-3625 1800);
FORCEPROP 1 LAST COMMENT_BODY TRUE
J 0
(-3995 1830);
DISPLAY 0.893617 (-3995 1830);
PAINT GREEN (-3995 1830);
DISPLAY INVISIBLE (-3995 1830);
FORCEADD OFFPAGE..2
(-3950 1475);
FORCEPROP 2 LAST $XR0 73 
J 0
(-3761 1475);
DISPLAY 0.638298 (-3761 1475);
PAINT MONO (-3761 1475);
FORCEPROP 2 LAST ROOM PVSA_CPU1_VSENSE_VR
J 0
(-4350 1550);
PAINT ORANGE (-4350 1550);
DISPLAY INVISIBLE (-4350 1550);
FORCEPROP 2 LAST CDS_LIB mstr_standard
J 0
(-3950 1475);
PAINT ORANGE (-3950 1475);
DISPLAY INVISIBLE (-3950 1475);
FORCEPROP 2 LAST PATH I18
J 0
(-3785 1535);
DISPLAY 1.021277 (-3785 1535);
PAINT ORANGE (-3785 1535);
DISPLAY INVISIBLE (-3785 1535);
FORCEPROP 2 LAST BOM_COST PROC_VRD_VCCIN_CPU0
J 0
(-3750 1525);
PAINT MONO (-3750 1525);
DISPLAY INVISIBLE (-3750 1525);
FORCEPROP 1 LAST OFFPAGE TRUE
J 0
(-3625 1350);
DISPLAY 0.893617 (-3625 1350);
PAINT GREEN (-3625 1350);
DISPLAY INVISIBLE (-3625 1350);
FORCEPROP 1 LAST COMMENT_BODY TRUE
J 0
(-3995 1380);
DISPLAY 0.893617 (-3995 1380);
PAINT GREEN (-3995 1380);
DISPLAY INVISIBLE (-3995 1380);
FORCEADD OFFPAGE..2
(-1475 4150);
FORCEPROP 2 LAST $XR0 206 
J 0
(-1286 4150);
DISPLAY 0.638298 (-1286 4150);
PAINT MONO (-1286 4150);
FORCEPROP 2 LAST ROOM PVSA_CPU1_PWR_VR
J 0
(-1875 4225);
DISPLAY 1.936170 (-1875 4225);
PAINT ORANGE (-1875 4225);
DISPLAY INVISIBLE (-1875 4225);
FORCEPROP 2 LAST CDS_LIB mstr_standard
J 0
(-1475 4150);
PAINT ORANGE (-1475 4150);
DISPLAY INVISIBLE (-1475 4150);
FORCEPROP 2 LAST PATH I2
J 0
(-1045 4200);
DISPLAY 1.021277 (-1045 4200);
PAINT ORANGE (-1045 4200);
DISPLAY INVISIBLE (-1045 4200);
FORCEPROP 2 LAST BOM_COST PROC_VRD_VCCIN_CPU0
J 0
(-1275 4200);
DISPLAY 1.446809 (-1275 4200);
PAINT MONO (-1275 4200);
DISPLAY INVISIBLE (-1275 4200);
FORCEPROP 1 LAST OFFPAGE TRUE
J 0
(-1150 4025);
DISPLAY 1.723404 (-1150 4025);
PAINT GREEN (-1150 4025);
DISPLAY INVISIBLE (-1150 4025);
FORCEPROP 1 LAST COMMENT_BODY TRUE
J 0
(-1520 4055);
DISPLAY 1.723404 (-1520 4055);
PAINT GREEN (-1520 4055);
DISPLAY INVISIBLE (-1520 4055);
FORCEADD VCC_CORE..1
(-6700 4250);
FORCEPROP 3 LASTPIN (-6700 4200) SIG_NAME VR_FET_SW_P12V_STBY_PVCCIN_CPU1\g
J 0
(-6690 4210);
DISPLAY 0.659574 (-6690 4210);
PAINT MONO (-6690 4210);
DISPLAY INVISIBLE (-6690 4210);
FORCEPROP 1 LAST HDL_POWER VR_FET_SW_P12V_STBY_PVCCIN_CPU1
J 1
(-6650 4300);
DISPLAY 0.617021 (-6650 4300);
PAINT GREEN (-6650 4300);
FORCEPROP 1 LAST PATH I21
J 0
(-6650 4275);
DISPLAY 0.872340 (-6650 4275);
PAINT AQUA (-6650 4275);
DISPLAY INVISIBLE (-6650 4275);
FORCEPROP 2 LAST CDS_LIB mstr_symbols
J 0
(-6700 4250);
PAINT ORANGE (-6700 4250);
DISPLAY INVISIBLE (-6700 4250);
FORCEADD CAP..1
(-5200 3850);
FORCEPROP 1 LASTPIN (-5200 3950) $PN 1
J 0
(-5190 3930);
DISPLAY 0.617021 (-5190 3930);
PAINT ORANGE (-5190 3930);
FORCEPROP 1 LAST PART_NUMBER A36096-155
J 0
(-5000 3875);
DISPLAY 0.617021 (-5000 3875);
PAINT BLUE (-5000 3875);
FORCEPROP 1 LAST PACK_TYPE 0402
J 0
(-5000 3825);
DISPLAY 0.617021 (-5000 3825);
PAINT SKYBLUE (-5000 3825);
FORCEPROP 1 LAST MATERIAL X7R
J 0
(-5000 3925);
DISPLAY 0.617021 (-5000 3925);
PAINT SKYBLUE (-5000 3925);
FORCEPROP 1 LAST VALUE 0.22UF
J 0
(-5150 3875);
DISPLAY 0.617021 (-5150 3875);
PAINT SKYBLUE (-5150 3875);
FORCEPROP 1 LAST VOLTAGE 16V
J 0
(-5150 3825);
DISPLAY 0.617021 (-5150 3825);
PAINT SKYBLUE (-5150 3825);
FORCEPROP 1 LASTPIN (-5200 3750) $PN 2
J 0
(-5190 3730);
DISPLAY 0.617021 (-5190 3730);
PAINT ORANGE (-5190 3730);
FORCEPROP 1 LAST TOLERANCE 10%
J 0
(-5150 3775);
DISPLAY 0.617021 (-5150 3775);
PAINT SKYBLUE (-5150 3775);
FORCEPROP 1 LAST LOCATION C1C4
J 0
(-5150 3925);
DISPLAY 0.617021 (-5150 3925);
PAINT AQUA (-5150 3925);
FORCEPROP 2 LAST CDS_LIB mstr_discrete
J 0
(-5200 3850);
PAINT ORANGE (-5200 3850);
DISPLAY INVISIBLE (-5200 3850);
FORCEPROP 2 LAST SEC_TYPE 0402
J 0
(-5150 4050);
DISPLAY 1.021277 (-5150 4050);
PAINT ORANGE (-5150 4050);
DISPLAY INVISIBLE (-5150 4050);
FORCEPROP 2 LAST SEC 1
J 0
(-5150 4050);
DISPLAY 0.680851 (-5150 4050);
PAINT MONO (-5150 4050);
DISPLAY INVISIBLE (-5150 4050);
FORCEPROP 2 LAST CDS_LOCATION C1C4
J 0
(-5150 3925);
DISPLAY 0.617021 (-5150 3925);
PAINT AQUA (-5150 3925);
DISPLAY INVISIBLE (-5150 3925);
FORCEPROP 1 LAST PATH I22
J 0
(-5150 4000);
DISPLAY 0.978723 (-5150 4000);
PAINT WHITE (-5150 4000);
DISPLAY INVISIBLE (-5150 4000);
FORCEPROP 2 LAST ROOM PVSA_CPU1_PWR_VR
J 0
(-5150 4000);
DISPLAY 1.361702 (-5150 4000);
PAINT ORANGE (-5150 4000);
DISPLAY INVISIBLE (-5150 4000);
FORCEADD CAP..1
R 2
(-6125 3250);
FORCEPROP 1 LAST LOCATION C1C12
J 2
(-6175 3350);
DISPLAY 0.617021 (-6175 3350);
PAINT AQUA (-6175 3350);
FORCEPROP 1 LAST VALUE 0.220UF
J 2
(-6175 3300);
DISPLAY 0.617021 (-6175 3300);
PAINT SKYBLUE (-6175 3300);
FORCEPROP 1 LAST VOLTAGE 16V
J 2
(-6175 3250);
DISPLAY 0.617021 (-6175 3250);
PAINT SKYBLUE (-6175 3250);
FORCEPROP 1 LAST MATERIAL X7R
J 2
(-6175 3150);
DISPLAY 0.617021 (-6175 3150);
PAINT SKYBLUE (-6175 3150);
FORCEPROP 1 LAST PACK_TYPE 0402
J 2
(-6175 3050);
DISPLAY 0.617021 (-6175 3050);
PAINT SKYBLUE (-6175 3050);
FORCEPROP 1 LAST TOLERANCE 10%
J 2
(-6175 3200);
DISPLAY 0.617021 (-6175 3200);
PAINT SKYBLUE (-6175 3200);
FORCEPROP 1 LASTPIN (-6125 3350) $PN 1
J 2
(-6135 3330);
DISPLAY 0.617021 (-6135 3330);
PAINT ORANGE (-6135 3330);
FORCEPROP 1 LASTPIN (-6125 3150) $PN 2
J 2
(-6135 3130);
DISPLAY 0.617021 (-6135 3130);
PAINT ORANGE (-6135 3130);
FORCEPROP 1 LAST PART_NUMBER A36096-104
J 2
(-6175 3100);
DISPLAY 0.617021 (-6175 3100);
PAINT BLUE (-6175 3100);
FORCEPROP 2 LAST CDS_LIB mstr_discrete
J 0
(-6125 3250);
PAINT ORANGE (-6125 3250);
DISPLAY INVISIBLE (-6125 3250);
FORCEPROP 1 LAST PATH I24
J 2
(-6175 3400);
DISPLAY 0.978723 (-6175 3400);
PAINT WHITE (-6175 3400);
DISPLAY INVISIBLE (-6175 3400);
FORCEPROP 2 LAST SEC_TYPE 0402
J 0
(-6175 3450);
DISPLAY 1.021277 (-6175 3450);
PAINT ORANGE (-6175 3450);
DISPLAY INVISIBLE (-6175 3450);
FORCEPROP 2 LAST ROOM PVSA_CPU1_PWR_VR
J 0
(-6175 3400);
DISPLAY 1.361702 (-6175 3400);
PAINT ORANGE (-6175 3400);
DISPLAY INVISIBLE (-6175 3400);
FORCEPROP 0 LAST SPOF TRUE
J 0
(-6175 3450);
DISPLAY 1.021277 (-6175 3450);
PAINT ORANGE (-6175 3450);
DISPLAY INVISIBLE (-6175 3450);
FORCEPROP 2 LAST SEC 1
J 0
(-6175 3450);
DISPLAY 0.680851 (-6175 3450);
PAINT MONO (-6175 3450);
DISPLAY INVISIBLE (-6175 3450);
FORCEPROP 2 LAST CDS_LOCATION C1C12
J 2
(-6175 3350);
DISPLAY 0.617021 (-6175 3350);
PAINT AQUA (-6175 3350);
DISPLAY INVISIBLE (-6175 3350);
FORCEADD CAP..1
(-5875 3825);
FORCEPROP 1 LAST LOCATION C1C5
J 0
(-5825 3925);
DISPLAY 0.617021 (-5825 3925);
PAINT AQUA (-5825 3925);
FORCEPROP 1 LAST VALUE 1.0UF
J 0
(-5825 3875);
DISPLAY 0.617021 (-5825 3875);
PAINT SKYBLUE (-5825 3875);
FORCEPROP 1 LAST PACK_TYPE 0402
J 0
(-5825 3600);
DISPLAY 0.617021 (-5825 3600);
PAINT SKYBLUE (-5825 3600);
FORCEPROP 1 LASTPIN (-5875 3725) $PN 2
J 0
(-5865 3705);
DISPLAY 0.617021 (-5865 3705);
PAINT ORANGE (-5865 3705);
FORCEPROP 1 LAST MATERIAL X6S
J 0
(-5825 3725);
DISPLAY 0.617021 (-5825 3725);
PAINT SKYBLUE (-5825 3725);
FORCEPROP 1 LAST PART_NUMBER D97712-011
J 0
(-5825 3650);
DISPLAY 0.617021 (-5825 3650);
PAINT BLUE (-5825 3650);
FORCEPROP 1 LASTPIN (-5875 3925) $PN 1
J 0
(-5865 3905);
DISPLAY 0.617021 (-5865 3905);
PAINT ORANGE (-5865 3905);
FORCEPROP 1 LAST VOLTAGE 16V
J 0
(-5825 3825);
DISPLAY 0.617021 (-5825 3825);
PAINT SKYBLUE (-5825 3825);
FORCEPROP 1 LAST TOLERANCE 10%
J 0
(-5825 3775);
DISPLAY 0.617021 (-5825 3775);
PAINT SKYBLUE (-5825 3775);
FORCEPROP 2 LAST ROOM PVSA_CPU1_PWR_VR
J 0
(-5825 3975);
DISPLAY 1.361702 (-5825 3975);
PAINT ORANGE (-5825 3975);
DISPLAY INVISIBLE (-5825 3975);
FORCEPROP 1 LAST PATH I26
J 0
(-5825 3975);
DISPLAY 0.978723 (-5825 3975);
PAINT WHITE (-5825 3975);
DISPLAY INVISIBLE (-5825 3975);
FORCEPROP 2 LAST CDS_LOCATION C1C5
J 0
(-5825 3925);
DISPLAY 0.617021 (-5825 3925);
PAINT AQUA (-5825 3925);
DISPLAY INVISIBLE (-5825 3925);
FORCEPROP 2 LAST SEC 1
J 0
(-5825 4025);
DISPLAY 0.680851 (-5825 4025);
PAINT MONO (-5825 4025);
DISPLAY INVISIBLE (-5825 4025);
FORCEPROP 2 LAST SEC_TYPE 0402
J 0
(-5825 4025);
DISPLAY 1.021277 (-5825 4025);
PAINT ORANGE (-5825 4025);
DISPLAY INVISIBLE (-5825 4025);
FORCEPROP 2 LAST CDS_LIB mstr_discrete
J 0
(-5875 3825);
PAINT ORANGE (-5875 3825);
DISPLAY INVISIBLE (-5875 3825);
FORCEADD CAP_A..1
(-6125 3850);
FORCEPROP 1 LAST LOCATION C1C17
J 0
(-6075 3950);
DISPLAY 0.617021 (-6075 3950);
PAINT AQUA (-6075 3950);
FORCEPROP 1 LAST PART_NUMBER A36096-030
J 0
(-6100 3675);
DISPLAY 0.617021 (-6100 3675);
PAINT BLUE (-6100 3675);
FORCEPROP 1 LAST VOLTAGE 16V
J 0
(-6075 3850);
DISPLAY 0.617021 (-6075 3850);
PAINT SKYBLUE (-6075 3850);
FORCEPROP 1 LAST PACK_TYPE 0402V
J 0
(-6075 3625);
DISPLAY 0.617021 (-6075 3625);
PAINT SKYBLUE (-6075 3625);
FORCEPROP 1 LAST VALUE 0.1UF
J 0
(-6075 3900);
DISPLAY 0.617021 (-6075 3900);
PAINT SKYBLUE (-6075 3900);
FORCEPROP 1 LAST TOLERANCE 10%
J 0
(-6075 3800);
DISPLAY 0.617021 (-6075 3800);
PAINT SKYBLUE (-6075 3800);
FORCEPROP 1 LASTPIN (-6125 3750) $PN 2
J 0
(-6115 3730);
DISPLAY 0.617021 (-6115 3730);
PAINT ORANGE (-6115 3730);
FORCEPROP 1 LASTPIN (-6125 3950) $PN 1
J 0
(-6115 3930);
DISPLAY 0.617021 (-6115 3930);
PAINT ORANGE (-6115 3930);
FORCEPROP 1 LAST MATERIAL X7R
J 0
(-6075 3750);
DISPLAY 0.617021 (-6075 3750);
PAINT SKYBLUE (-6075 3750);
FORCEPROP 2 LAST CDS_LIB dev_discrete
J 0
(-6125 3850);
PAINT ORANGE (-6125 3850);
DISPLAY INVISIBLE (-6125 3850);
FORCEPROP 2 LAST CDS_LOCATION C1C17
J 0
(-6075 3950);
DISPLAY 0.617021 (-6075 3950);
PAINT AQUA (-6075 3950);
DISPLAY INVISIBLE (-6075 3950);
FORCEPROP 1 LAST PATH I27
J 0
(-6075 4000);
DISPLAY 0.978723 (-6075 4000);
PAINT WHITE (-6075 4000);
DISPLAY INVISIBLE (-6075 4000);
FORCEPROP 2 LAST ROOM PVSA_CPU1_PWR_VR
J 0
(-6075 4000);
DISPLAY 1.361702 (-6075 4000);
PAINT ORANGE (-6075 4000);
DISPLAY INVISIBLE (-6075 4000);
FORCEPROP 2 LAST CDS_SEC 1
J 0
(-6075 4000);
PAINT ORANGE (-6075 4000);
DISPLAY INVISIBLE (-6075 4000);
FORCEPROP 2 LAST SEC_TYPE 0402V
J 0
(-6075 4050);
DISPLAY 1.021277 (-6075 4050);
PAINT ORANGE (-6075 4050);
DISPLAY INVISIBLE (-6075 4050);
FORCEPROP 2 LAST SEC 1
J 0
(-6075 4050);
DISPLAY 0.680851 (-6075 4050);
PAINT MONO (-6075 4050);
DISPLAY INVISIBLE (-6075 4050);
FORCEADD CAP..1
(-6375 3825);
FORCEPROP 1 LAST VALUE 1.0UF
J 0
(-6325 3875);
DISPLAY 0.617021 (-6325 3875);
PAINT SKYBLUE (-6325 3875);
FORCEPROP 1 LAST PART_NUMBER D97712-011
J 0
(-6350 3650);
DISPLAY 0.617021 (-6350 3650);
PAINT BLUE (-6350 3650);
FORCEPROP 1 LAST PACK_TYPE 0402
J 0
(-6325 3600);
DISPLAY 0.617021 (-6325 3600);
PAINT SKYBLUE (-6325 3600);
FORCEPROP 1 LAST MATERIAL X6S
J 0
(-6325 3725);
DISPLAY 0.617021 (-6325 3725);
PAINT SKYBLUE (-6325 3725);
FORCEPROP 1 LAST TOLERANCE 10%
J 0
(-6325 3775);
DISPLAY 0.617021 (-6325 3775);
PAINT SKYBLUE (-6325 3775);
FORCEPROP 1 LAST VOLTAGE 16V
J 0
(-6325 3825);
DISPLAY 0.617021 (-6325 3825);
PAINT SKYBLUE (-6325 3825);
FORCEPROP 1 LASTPIN (-6375 3725) $PN 2
J 0
(-6365 3705);
DISPLAY 0.617021 (-6365 3705);
PAINT ORANGE (-6365 3705);
FORCEPROP 1 LASTPIN (-6375 3925) $PN 1
J 0
(-6365 3905);
DISPLAY 0.617021 (-6365 3905);
PAINT ORANGE (-6365 3905);
FORCEPROP 1 LAST LOCATION C1C15
J 0
(-6325 3925);
DISPLAY 0.617021 (-6325 3925);
PAINT AQUA (-6325 3925);
FORCEPROP 2 LAST CDS_LIB mstr_discrete
J 0
(-6375 3825);
PAINT ORANGE (-6375 3825);
DISPLAY INVISIBLE (-6375 3825);
FORCEPROP 2 LAST CDS_LOCATION C1C15
J 0
(-6325 3925);
DISPLAY 0.617021 (-6325 3925);
PAINT AQUA (-6325 3925);
DISPLAY INVISIBLE (-6325 3925);
FORCEPROP 2 LAST SEC_TYPE 0402
J 0
(-6325 4025);
DISPLAY 1.021277 (-6325 4025);
PAINT ORANGE (-6325 4025);
DISPLAY INVISIBLE (-6325 4025);
FORCEPROP 2 LAST SEC 1
J 0
(-6325 4025);
DISPLAY 0.680851 (-6325 4025);
PAINT MONO (-6325 4025);
DISPLAY INVISIBLE (-6325 4025);
FORCEPROP 1 LAST PATH I28
J 0
(-6325 3975);
DISPLAY 0.978723 (-6325 3975);
PAINT WHITE (-6325 3975);
DISPLAY INVISIBLE (-6325 3975);
FORCEPROP 2 LAST ROOM PVSA_CPU1_PWR_VR
J 0
(-6325 3975);
DISPLAY 1.361702 (-6325 3975);
PAINT ORANGE (-6325 3975);
DISPLAY INVISIBLE (-6325 3975);
FORCEADD RES..1
(-5300 2325);
FORCEPROP 1 LAST PART_NUMBER G21796-017
J 0
(-5350 2425);
DISPLAY 0.617021 (-5350 2425);
PAINT BLUE (-5350 2425);
FORCEPROP 1 LASTPIN (-5200 2325) $PN 2
J 0
(-5238 2337);
DISPLAY 0.617021 (-5238 2337);
PAINT ORANGE (-5238 2337);
FORCEPROP 1 LAST LOCATION R1C12
J 0
(-5350 2375);
DISPLAY 0.617021 (-5350 2375);
PAINT AQUA (-5350 2375);
FORCEPROP 1 LAST WATTAGE 1/16W
J 2
(-5300 2200);
DISPLAY 0.617021 (-5300 2200);
PAINT SKYBLUE (-5300 2200);
FORCEPROP 1 LAST VALUE 100.0
J 2
(-5300 2250);
DISPLAY 0.617021 (-5300 2250);
PAINT SKYBLUE (-5300 2250);
FORCEPROP 1 LAST PACK_TYPE 0402
J 0
(-5375 2150);
DISPLAY 0.617021 (-5375 2150);
PAINT SKYBLUE (-5375 2150);
FORCEPROP 1 LASTPIN (-5400 2325) $PN 1
J 0
(-5388 2337);
DISPLAY 0.617021 (-5388 2337);
PAINT ORANGE (-5388 2337);
FORCEPROP 1 LAST TOLERANCE 1%
J 0
(-5250 2250);
DISPLAY 0.617021 (-5250 2250);
PAINT SKYBLUE (-5250 2250);
FORCEPROP 1 LAST MATERIAL CHIP
J 0
(-5275 2200);
PAINT SKYBLUE (-5275 2200);
DISPLAY INVISIBLE (-5275 2200);
FORCEPROP 2 LAST BOM_COST PROC_VRD_VCCIN_CPU0
J 0
(-5350 2475);
PAINT MONO (-5350 2475);
DISPLAY INVISIBLE (-5350 2475);
FORCEPROP 2 LAST CDS_LIB mstr_discrete
J 0
(-5300 2325);
PAINT ORANGE (-5300 2325);
DISPLAY INVISIBLE (-5300 2325);
FORCEPROP 2 LAST ROOM PVSA_CPU1_VSENSE_VR
J 0
(-5350 2425);
PAINT ORANGE (-5350 2425);
DISPLAY INVISIBLE (-5350 2425);
FORCEPROP 1 LAST PATH I29
J 0
(-5350 2475);
DISPLAY 0.978723 (-5350 2475);
PAINT WHITE (-5350 2475);
DISPLAY INVISIBLE (-5350 2475);
FORCEPROP 2 LAST CDS_LOCATION R1C12
J 0
(-5350 2375);
DISPLAY 0.617021 (-5350 2375);
PAINT AQUA (-5350 2375);
DISPLAY INVISIBLE (-5350 2375);
FORCEPROP 2 LAST SEC 1
J 0
(-5335 2535);
DISPLAY 0.680851 (-5335 2535);
PAINT MONO (-5335 2535);
DISPLAY INVISIBLE (-5335 2535);
FORCEPROP 2 LAST SEC_TYPE 0402
J 0
(-5335 2535);
DISPLAY 1.021277 (-5335 2535);
PAINT ORANGE (-5335 2535);
DISPLAY INVISIBLE (-5335 2535);
FORCEADD GND..1
(-4450 950);
FORCEPROP 3 LASTPIN (-4450 1000) SIG_NAME GND\g
J 0
(-4440 1010);
DISPLAY 0.659574 (-4440 1010);
PAINT MONO (-4440 1010);
DISPLAY INVISIBLE (-4440 1010);
FORCEPROP 1 LAST SIZE 1B
J 0
(-4375 900);
DISPLAY 0.893617 (-4375 900);
PAINT GREEN (-4375 900);
DISPLAY INVISIBLE (-4375 900);
FORCEPROP 2 LAST CDS_LIB mstr_symbols
J 0
(-4450 950);
PAINT ORANGE (-4450 950);
DISPLAY INVISIBLE (-4450 950);
FORCEPROP 1 LAST PATH I30
J 0
(-4375 950);
DISPLAY 0.872340 (-4375 950);
PAINT AQUA (-4375 950);
DISPLAY INVISIBLE (-4375 950);
FORCEPROP 1 LAST VOLTAGE 0
J 0
(-4450 950);
PAINT SKYBLUE (-4450 950);
DISPLAY INVISIBLE (-4450 950);
FORCEPROP 2 LAST BOM_COST PROC_VRD_VCCIN_CPU0
J 0
(-4825 1025);
PAINT MONO (-4825 1025);
DISPLAY INVISIBLE (-4825 1025);
FORCEPROP 2 LAST ROOM PVSA_CPU1_VSENSE_VR
J 0
(-5000 1025);
PAINT ORANGE (-5000 1025);
DISPLAY INVISIBLE (-5000 1025);
FORCEPROP 1 LAST BODY_TYPE PLUMBING
J 0
(-4495 907);
DISPLAY 0.340426 (-4495 907);
PAINT GREEN (-4495 907);
DISPLAY INVISIBLE (-4495 907);
FORCEPROP 1 LAST HDL_POWER GND
J 0
(-4450 1100);
DISPLAY 0.893617 (-4450 1100);
PAINT GREEN (-4450 1100);
DISPLAY INVISIBLE (-4450 1100);
FORCEADD RES..1
(-5275 1925);
FORCEPROP 1 LAST WATTAGE 1/16W
J 2
(-5300 1775);
DISPLAY 0.617021 (-5300 1775);
PAINT SKYBLUE (-5300 1775);
FORCEPROP 1 LAST PACK_TYPE 0402
J 0
(-5400 1725);
DISPLAY 0.617021 (-5400 1725);
PAINT SKYBLUE (-5400 1725);
FORCEPROP 1 LAST VALUE 0.0
J 2
(-5300 1850);
DISPLAY 0.617021 (-5300 1850);
PAINT SKYBLUE (-5300 1850);
FORCEPROP 1 LAST MATERIAL CHIP
J 0
(-5275 1775);
DISPLAY 0.617021 (-5275 1775);
PAINT SKYBLUE (-5275 1775);
FORCEPROP 1 LASTPIN (-5375 1925) $PN 1
J 0
(-5363 1937);
DISPLAY 0.617021 (-5363 1937);
PAINT ORANGE (-5363 1937);
FORCEPROP 1 LAST LOCATION R1C7
J 0
(-5325 1975);
DISPLAY 0.617021 (-5325 1975);
PAINT AQUA (-5325 1975);
FORCEPROP 1 LAST TOLERANCE 5%
J 0
(-5275 1850);
DISPLAY 0.617021 (-5275 1850);
PAINT SKYBLUE (-5275 1850);
FORCEPROP 1 LASTPIN (-5175 1925) $PN 2
J 0
(-5213 1937);
DISPLAY 0.617021 (-5213 1937);
PAINT ORANGE (-5213 1937);
FORCEPROP 1 LAST PART_NUMBER G21497-005
J 0
(-5400 2025);
DISPLAY 0.617021 (-5400 2025);
PAINT BLUE (-5400 2025);
FORCEPROP 2 LAST CDS_LIB mstr_discrete
J 0
(-5275 1925);
PAINT ORANGE (-5275 1925);
DISPLAY INVISIBLE (-5275 1925);
FORCEPROP 2 LAST CDS_LOCATION R1C7
J 0
(-5325 1975);
DISPLAY 0.617021 (-5325 1975);
PAINT AQUA (-5325 1975);
DISPLAY INVISIBLE (-5325 1975);
FORCEPROP 2 LAST ROOM PVSA_CPU1_VSENSE_VR
J 0
(-5325 2025);
PAINT ORANGE (-5325 2025);
DISPLAY INVISIBLE (-5325 2025);
FORCEPROP 2 LAST BOM_COST PROC_VRD_VCCIN_CPU0
J 0
(-5400 2075);
PAINT MONO (-5400 2075);
DISPLAY INVISIBLE (-5400 2075);
FORCEPROP 1 LAST PATH I31
J 0
(-5325 2075);
DISPLAY 0.978723 (-5325 2075);
PAINT WHITE (-5325 2075);
DISPLAY INVISIBLE (-5325 2075);
FORCEPROP 2 LAST SEC 1
J 0
(-5310 2135);
DISPLAY 0.680851 (-5310 2135);
PAINT MONO (-5310 2135);
DISPLAY INVISIBLE (-5310 2135);
FORCEPROP 2 LAST SEC_TYPE 0402
J 0
(-5310 2135);
DISPLAY 1.021277 (-5310 2135);
PAINT ORANGE (-5310 2135);
DISPLAY INVISIBLE (-5310 2135);
FORCEADD RES..1
(-5275 1475);
FORCEPROP 1 LAST PACK_TYPE 0402
J 0
(-5400 1275);
DISPLAY 0.617021 (-5400 1275);
PAINT SKYBLUE (-5400 1275);
FORCEPROP 1 LAST MATERIAL CHIP
J 0
(-5275 1325);
DISPLAY 0.617021 (-5275 1325);
PAINT SKYBLUE (-5275 1325);
FORCEPROP 1 LAST PART_NUMBER G21497-005
J 0
(-5400 1575);
DISPLAY 0.617021 (-5400 1575);
PAINT BLUE (-5400 1575);
FORCEPROP 1 LAST LOCATION R1C5
J 0
(-5325 1525);
DISPLAY 0.617021 (-5325 1525);
PAINT AQUA (-5325 1525);
FORCEPROP 1 LAST TOLERANCE 5%
J 0
(-5275 1400);
DISPLAY 0.617021 (-5275 1400);
PAINT SKYBLUE (-5275 1400);
FORCEPROP 1 LASTPIN (-5175 1475) $PN 2
J 0
(-5213 1487);
DISPLAY 0.617021 (-5213 1487);
PAINT ORANGE (-5213 1487);
FORCEPROP 1 LAST WATTAGE 1/16W
J 2
(-5300 1325);
DISPLAY 0.617021 (-5300 1325);
PAINT SKYBLUE (-5300 1325);
FORCEPROP 1 LAST VALUE 0.0
J 2
(-5300 1400);
DISPLAY 0.617021 (-5300 1400);
PAINT SKYBLUE (-5300 1400);
FORCEPROP 1 LASTPIN (-5375 1475) $PN 1
J 0
(-5363 1487);
DISPLAY 0.617021 (-5363 1487);
PAINT ORANGE (-5363 1487);
FORCEPROP 2 LAST CDS_LIB mstr_discrete
J 0
(-5275 1475);
PAINT ORANGE (-5275 1475);
DISPLAY INVISIBLE (-5275 1475);
FORCEPROP 2 LAST CDS_LOCATION R1C5
J 0
(-5325 1525);
DISPLAY 0.617021 (-5325 1525);
PAINT AQUA (-5325 1525);
DISPLAY INVISIBLE (-5325 1525);
FORCEPROP 2 LAST BOM_COST PROC_VRD_VCCIN_CPU0
J 0
(-5400 1625);
PAINT MONO (-5400 1625);
DISPLAY INVISIBLE (-5400 1625);
FORCEPROP 2 LAST ROOM PVSA_CPU1_VSENSE_VR
J 0
(-5325 1575);
PAINT ORANGE (-5325 1575);
DISPLAY INVISIBLE (-5325 1575);
FORCEPROP 1 LAST PATH I32
J 0
(-5325 1625);
DISPLAY 0.978723 (-5325 1625);
PAINT WHITE (-5325 1625);
DISPLAY INVISIBLE (-5325 1625);
FORCEPROP 2 LAST SEC 1
J 0
(-5310 1685);
DISPLAY 0.680851 (-5310 1685);
PAINT MONO (-5310 1685);
DISPLAY INVISIBLE (-5310 1685);
FORCEPROP 2 LAST SEC_TYPE 0402
J 0
(-5310 1685);
DISPLAY 1.021277 (-5310 1685);
PAINT ORANGE (-5310 1685);
DISPLAY INVISIBLE (-5310 1685);
FORCEADD RES..1
(-5275 1100);
FORCEPROP 1 LAST WATTAGE 1/16W
J 2
(-5275 975);
DISPLAY 0.617021 (-5275 975);
PAINT SKYBLUE (-5275 975);
FORCEPROP 1 LAST PACK_TYPE 0402
J 0
(-5350 925);
DISPLAY 0.617021 (-5350 925);
PAINT SKYBLUE (-5350 925);
FORCEPROP 1 LAST VALUE 100.0
J 2
(-5275 1025);
DISPLAY 0.617021 (-5275 1025);
PAINT SKYBLUE (-5275 1025);
FORCEPROP 1 LASTPIN (-5375 1100) $PN 1
J 0
(-5363 1112);
DISPLAY 0.617021 (-5363 1112);
PAINT ORANGE (-5363 1112);
FORCEPROP 1 LAST LOCATION R1C4
J 0
(-5325 1150);
DISPLAY 0.617021 (-5325 1150);
PAINT AQUA (-5325 1150);
FORCEPROP 1 LAST TOLERANCE 1%
J 0
(-5225 1025);
DISPLAY 0.617021 (-5225 1025);
PAINT SKYBLUE (-5225 1025);
FORCEPROP 1 LASTPIN (-5175 1100) $PN 2
J 0
(-5213 1112);
DISPLAY 0.617021 (-5213 1112);
PAINT ORANGE (-5213 1112);
FORCEPROP 1 LAST PART_NUMBER G21796-017
J 0
(-5325 1200);
DISPLAY 0.617021 (-5325 1200);
PAINT BLUE (-5325 1200);
FORCEPROP 1 LAST MATERIAL CHIP
J 0
(-5250 975);
PAINT SKYBLUE (-5250 975);
DISPLAY INVISIBLE (-5250 975);
FORCEPROP 2 LAST CDS_LIB mstr_discrete
J 0
(-5275 1100);
PAINT ORANGE (-5275 1100);
DISPLAY INVISIBLE (-5275 1100);
FORCEPROP 2 LAST CDS_LOCATION R1C4
J 0
(-5325 1150);
DISPLAY 0.617021 (-5325 1150);
PAINT AQUA (-5325 1150);
DISPLAY INVISIBLE (-5325 1150);
FORCEPROP 2 LAST ROOM PVSA_CPU1_VSENSE_VR
J 0
(-5325 1200);
PAINT ORANGE (-5325 1200);
DISPLAY INVISIBLE (-5325 1200);
FORCEPROP 1 LAST PATH I33
J 0
(-5325 1250);
DISPLAY 0.978723 (-5325 1250);
PAINT WHITE (-5325 1250);
DISPLAY INVISIBLE (-5325 1250);
FORCEPROP 2 LAST BOM_COST PROC_VRD_VCCIN_CPU0
J 0
(-5325 1250);
PAINT MONO (-5325 1250);
DISPLAY INVISIBLE (-5325 1250);
FORCEPROP 2 LAST SEC_TYPE 0402
J 0
(-5310 1310);
DISPLAY 1.021277 (-5310 1310);
PAINT ORANGE (-5310 1310);
DISPLAY INVISIBLE (-5310 1310);
FORCEPROP 2 LAST SEC 1
J 0
(-5310 1310);
DISPLAY 0.680851 (-5310 1310);
PAINT MONO (-5310 1310);
DISPLAY INVISIBLE (-5310 1310);
FORCEADD RES..2
(-5950 1725);
FORCEPROP 1 LAST VALUE 1.00K
J 0
(-5905 1800);
DISPLAY 0.617021 (-5905 1800);
PAINT SKYBLUE (-5905 1800);
FORCEPROP 1 LASTPIN (-5950 1625) $PN 2
J 0
(-5945 1635);
DISPLAY 0.617021 (-5945 1635);
PAINT ORANGE (-5945 1635);
FORCEPROP 1 LASTPIN (-5950 1825) $PN 1
J 0
(-5945 1787);
DISPLAY 0.617021 (-5945 1787);
PAINT ORANGE (-5945 1787);
FORCEPROP 1 LAST WATTAGE 1/16W
J 0
(-5910 1700);
DISPLAY 0.617021 (-5910 1700);
PAINT SKYBLUE (-5910 1700);
FORCEPROP 1 LAST TOLERANCE 1%
J 0
(-5905 1750);
DISPLAY 0.617021 (-5905 1750);
PAINT SKYBLUE (-5905 1750);
FORCEPROP 1 LAST LOCATION R1C6
J 0
(-5905 1850);
DISPLAY 0.617021 (-5905 1850);
PAINT AQUA (-5905 1850);
FORCEPROP 1 LAST MATERIAL EMPTY
J 0
(-5910 1650);
DISPLAY 0.617021 (-5910 1650);
PAINT RED (-5910 1650);
FORCEPROP 1 LAST PART_NUMBER G21796-026
J 0
(-5910 1600);
DISPLAY 0.617021 (-5910 1600);
PAINT BLUE (-5910 1600);
FORCEPROP 1 LAST PACK_TYPE 0402
J 0
(-5910 1550);
DISPLAY 0.617021 (-5910 1550);
PAINT SKYBLUE (-5910 1550);
FORCEPROP 2 LAST CDS_LIB mstr_discrete
J 0
(-5950 1725);
PAINT ORANGE (-5950 1725);
DISPLAY INVISIBLE (-5950 1725);
FORCEPROP 2 LAST CDS_LOCATION R1C6
J 0
(-5905 1850);
DISPLAY 0.617021 (-5905 1850);
PAINT AQUA (-5905 1850);
DISPLAY INVISIBLE (-5905 1850);
FORCEPROP 2 LAST ROOM PVSA_CPU1_VSENSE_VR
J 0
(-5900 1900);
PAINT MONO (-5900 1900);
DISPLAY INVISIBLE (-5900 1900);
FORCEPROP 1 LAST PATH I34
J 0
(-5900 1900);
DISPLAY 0.978723 (-5900 1900);
PAINT WHITE (-5900 1900);
DISPLAY INVISIBLE (-5900 1900);
FORCEPROP 2 LAST BOM_COST PROC_VRD_VCCIN_CPU0
J 0
(-5900 1900);
PAINT MONO (-5900 1900);
DISPLAY INVISIBLE (-5900 1900);
FORCEPROP 2 LAST NO_XNET_CONNECTION 1
J 0
(-5900 1950);
PAINT MONO (-5900 1950);
DISPLAY INVISIBLE (-5900 1950);
FORCEPROP 2 LAST SEC 1
J 0
(-5885 1960);
DISPLAY 0.680851 (-5885 1960);
PAINT MONO (-5885 1960);
DISPLAY INVISIBLE (-5885 1960);
FORCEPROP 2 LAST SEC_TYPE 0402
J 0
(-5885 1960);
DISPLAY 1.021277 (-5885 1960);
PAINT ORANGE (-5885 1960);
DISPLAY INVISIBLE (-5885 1960);
FORCEADD CAP..1
(-6625 3825);
FORCEPROP 1 LAST PACK_TYPE 0805
J 0
(-6575 3600);
DISPLAY 0.617021 (-6575 3600);
PAINT SKYBLUE (-6575 3600);
FORCEPROP 1 LAST PART_NUMBER C95333-007
J 0
(-6600 3650);
DISPLAY 0.617021 (-6600 3650);
PAINT BLUE (-6600 3650);
FORCEPROP 1 LAST MATERIAL X6S
J 0
(-6575 3725);
DISPLAY 0.617021 (-6575 3725);
PAINT SKYBLUE (-6575 3725);
FORCEPROP 1 LAST TOLERANCE 10%
J 0
(-6575 3775);
DISPLAY 0.617021 (-6575 3775);
PAINT SKYBLUE (-6575 3775);
FORCEPROP 1 LAST LOCATION C9N13
J 0
(-6575 3925);
DISPLAY 0.617021 (-6575 3925);
PAINT AQUA (-6575 3925);
FORCEPROP 1 LAST VALUE 10UF
J 0
(-6575 3875);
DISPLAY 0.617021 (-6575 3875);
PAINT SKYBLUE (-6575 3875);
FORCEPROP 1 LAST VOLTAGE 16V
J 0
(-6575 3825);
DISPLAY 0.617021 (-6575 3825);
PAINT SKYBLUE (-6575 3825);
FORCEPROP 1 LASTPIN (-6625 3725) $PN 2
J 0
(-6615 3705);
DISPLAY 0.617021 (-6615 3705);
PAINT ORANGE (-6615 3705);
FORCEPROP 1 LASTPIN (-6625 3925) $PN 1
J 0
(-6615 3905);
DISPLAY 0.617021 (-6615 3905);
PAINT ORANGE (-6615 3905);
FORCEPROP 2 LAST CDS_LIB mstr_discrete
J 0
(-6625 3825);
PAINT ORANGE (-6625 3825);
DISPLAY INVISIBLE (-6625 3825);
FORCEPROP 2 LAST ROOM PVSA_CPU1_PWR_VR
J 0
(-6575 3975);
DISPLAY 1.361702 (-6575 3975);
PAINT ORANGE (-6575 3975);
DISPLAY INVISIBLE (-6575 3975);
FORCEPROP 1 LAST PATH I35
J 0
(-6575 3975);
DISPLAY 0.978723 (-6575 3975);
PAINT WHITE (-6575 3975);
DISPLAY INVISIBLE (-6575 3975);
FORCEPROP 2 LAST CDS_LOCATION C9N13
J 0
(-6575 3925);
DISPLAY 0.617021 (-6575 3925);
PAINT AQUA (-6575 3925);
DISPLAY INVISIBLE (-6575 3925);
FORCEPROP 2 LAST SEC 1
J 0
(-6575 4025);
DISPLAY 0.680851 (-6575 4025);
PAINT MONO (-6575 4025);
DISPLAY INVISIBLE (-6575 4025);
FORCEPROP 2 LAST SEC_TYPE 0805
J 0
(-6575 4025);
DISPLAY 1.021277 (-6575 4025);
PAINT ORANGE (-6575 4025);
DISPLAY INVISIBLE (-6575 4025);
FORCEADD CAP..1
(-6900 3850);
FORCEPROP 1 LAST VALUE 10UF
J 0
(-6850 3900);
DISPLAY 0.617021 (-6850 3900);
PAINT SKYBLUE (-6850 3900);
FORCEPROP 1 LAST VOLTAGE 16V
J 0
(-6850 3850);
DISPLAY 0.617021 (-6850 3850);
PAINT SKYBLUE (-6850 3850);
FORCEPROP 1 LAST PART_NUMBER C95333-007
J 0
(-6875 3675);
DISPLAY 0.617021 (-6875 3675);
PAINT BLUE (-6875 3675);
FORCEPROP 1 LAST PACK_TYPE 0805
J 0
(-6850 3625);
DISPLAY 0.617021 (-6850 3625);
PAINT SKYBLUE (-6850 3625);
FORCEPROP 1 LAST LOCATION C9N19
J 0
(-6850 3950);
DISPLAY 0.617021 (-6850 3950);
PAINT AQUA (-6850 3950);
FORCEPROP 1 LAST TOLERANCE 10%
J 0
(-6850 3800);
DISPLAY 0.617021 (-6850 3800);
PAINT SKYBLUE (-6850 3800);
FORCEPROP 1 LAST MATERIAL X6S
J 0
(-6850 3750);
DISPLAY 0.617021 (-6850 3750);
PAINT SKYBLUE (-6850 3750);
FORCEPROP 1 LASTPIN (-6900 3750) $PN 2
J 0
(-6890 3730);
DISPLAY 0.617021 (-6890 3730);
PAINT ORANGE (-6890 3730);
FORCEPROP 1 LASTPIN (-6900 3950) $PN 1
J 0
(-6890 3930);
DISPLAY 0.617021 (-6890 3930);
PAINT ORANGE (-6890 3930);
FORCEPROP 1 LAST PATH I36
J 0
(-6850 4000);
DISPLAY 0.978723 (-6850 4000);
PAINT WHITE (-6850 4000);
DISPLAY INVISIBLE (-6850 4000);
FORCEPROP 2 LAST ROOM PVSA_CPU1_PWR_VR
J 0
(-6850 4000);
DISPLAY 1.361702 (-6850 4000);
PAINT ORANGE (-6850 4000);
DISPLAY INVISIBLE (-6850 4000);
FORCEPROP 2 LAST SEC_TYPE 0805
J 0
(-6850 4050);
DISPLAY 1.021277 (-6850 4050);
PAINT ORANGE (-6850 4050);
DISPLAY INVISIBLE (-6850 4050);
FORCEPROP 2 LAST SEC 1
J 0
(-6850 4050);
DISPLAY 0.680851 (-6850 4050);
PAINT MONO (-6850 4050);
DISPLAY INVISIBLE (-6850 4050);
FORCEPROP 2 LAST CDS_LOCATION C9N19
J 0
(-6850 3950);
DISPLAY 0.617021 (-6850 3950);
PAINT AQUA (-6850 3950);
DISPLAY INVISIBLE (-6850 3950);
FORCEPROP 2 LAST CDS_LIB mstr_discrete
J 0
(-6900 3850);
PAINT ORANGE (-6900 3850);
DISPLAY INVISIBLE (-6900 3850);
FORCEADD CAP..1
(-7175 3850);
FORCEPROP 1 LAST LOCATION C9N21
J 0
(-7125 3950);
DISPLAY 0.617021 (-7125 3950);
PAINT AQUA (-7125 3950);
FORCEPROP 1 LAST PACK_TYPE 0805
J 0
(-7125 3625);
DISPLAY 0.617021 (-7125 3625);
PAINT SKYBLUE (-7125 3625);
FORCEPROP 1 LAST VOLTAGE 16V
J 0
(-7125 3850);
DISPLAY 0.617021 (-7125 3850);
PAINT SKYBLUE (-7125 3850);
FORCEPROP 1 LAST TOLERANCE 10%
J 0
(-7125 3800);
DISPLAY 0.617021 (-7125 3800);
PAINT SKYBLUE (-7125 3800);
FORCEPROP 1 LASTPIN (-7175 3750) $PN 2
J 0
(-7165 3730);
DISPLAY 0.617021 (-7165 3730);
PAINT ORANGE (-7165 3730);
FORCEPROP 1 LASTPIN (-7175 3950) $PN 1
J 0
(-7165 3930);
DISPLAY 0.617021 (-7165 3930);
PAINT ORANGE (-7165 3930);
FORCEPROP 1 LAST VALUE 10UF
J 0
(-7125 3900);
DISPLAY 0.617021 (-7125 3900);
PAINT SKYBLUE (-7125 3900);
FORCEPROP 1 LAST MATERIAL X6S
J 0
(-7125 3750);
DISPLAY 0.617021 (-7125 3750);
PAINT SKYBLUE (-7125 3750);
FORCEPROP 1 LAST PART_NUMBER C95333-007
J 0
(-7150 3675);
DISPLAY 0.617021 (-7150 3675);
PAINT BLUE (-7150 3675);
FORCEPROP 2 LAST CDS_LIB mstr_discrete
J 0
(-7175 3850);
PAINT ORANGE (-7175 3850);
DISPLAY INVISIBLE (-7175 3850);
FORCEPROP 2 LAST CDS_LOCATION C9N21
J 0
(-7125 3950);
DISPLAY 0.617021 (-7125 3950);
PAINT AQUA (-7125 3950);
DISPLAY INVISIBLE (-7125 3950);
FORCEPROP 2 LAST ROOM PVSA_CPU1_PWR_VR
J 0
(-7125 4000);
DISPLAY 1.361702 (-7125 4000);
PAINT ORANGE (-7125 4000);
DISPLAY INVISIBLE (-7125 4000);
FORCEPROP 1 LAST PATH I38
J 0
(-7125 4000);
DISPLAY 0.978723 (-7125 4000);
PAINT WHITE (-7125 4000);
DISPLAY INVISIBLE (-7125 4000);
FORCEPROP 2 LAST SEC_TYPE 0805
J 0
(-7125 4050);
DISPLAY 1.021277 (-7125 4050);
PAINT ORANGE (-7125 4050);
DISPLAY INVISIBLE (-7125 4050);
FORCEPROP 2 LAST SEC 1
J 0
(-7125 4050);
DISPLAY 0.680851 (-7125 4050);
PAINT MONO (-7125 4050);
DISPLAY INVISIBLE (-7125 4050);
FORCEADD GND..1
(-7175 3425);
FORCEPROP 3 LASTPIN (-7175 3475) SIG_NAME GND\g
J 0
(-7165 3485);
DISPLAY 0.659574 (-7165 3485);
PAINT MONO (-7165 3485);
DISPLAY INVISIBLE (-7165 3485);
FORCEPROP 1 LAST VOLTAGE 0
J 0
(-7175 3425);
PAINT SKYBLUE (-7175 3425);
DISPLAY INVISIBLE (-7175 3425);
FORCEPROP 2 LAST CDS_LIB mstr_symbols
J 0
(-7175 3425);
PAINT ORANGE (-7175 3425);
DISPLAY INVISIBLE (-7175 3425);
FORCEPROP 1 LAST PATH I39
J 0
(-7100 3425);
DISPLAY 0.872340 (-7100 3425);
PAINT AQUA (-7100 3425);
DISPLAY INVISIBLE (-7100 3425);
FORCEPROP 1 LAST SIZE 1B
J 0
(-7100 3375);
DISPLAY 1.723404 (-7100 3375);
PAINT GREEN (-7100 3375);
DISPLAY INVISIBLE (-7100 3375);
FORCEPROP 2 LAST BOM_COST PROC_VRD_VCCIN_CPU0
J 0
(-7550 3500);
DISPLAY 1.446809 (-7550 3500);
PAINT MONO (-7550 3500);
DISPLAY INVISIBLE (-7550 3500);
FORCEPROP 2 LAST ROOM PVSA_CPU1_PWR_VR
J 0
(-7725 3500);
DISPLAY 1.936170 (-7725 3500);
PAINT ORANGE (-7725 3500);
DISPLAY INVISIBLE (-7725 3500);
FORCEPROP 1 LAST BODY_TYPE PLUMBING
J 0
(-7220 3382);
DISPLAY 0.340426 (-7220 3382);
PAINT GREEN (-7220 3382);
DISPLAY INVISIBLE (-7220 3382);
FORCEPROP 1 LAST HDL_POWER GND
J 0
(-7175 3575);
DISPLAY 1.723404 (-7175 3575);
PAINT GREEN (-7175 3575);
DISPLAY INVISIBLE (-7175 3575);
FORCEADD OFFPAGE..1
(-7400 1975);
FORCEPROP 2 LAST $XR0 206 
J 0
(-7652 1975);
DISPLAY 0.638298 (-7652 1975);
PAINT MONO (-7652 1975);
FORCEPROP 2 LAST CDS_LIB mstr_standard
J 0
(-7400 1975);
PAINT ORANGE (-7400 1975);
DISPLAY INVISIBLE (-7400 1975);
FORCEPROP 2 LAST PATH I40
J 0
(-7635 2010);
DISPLAY 1.021277 (-7635 2010);
PAINT ORANGE (-7635 2010);
DISPLAY INVISIBLE (-7635 2010);
FORCEPROP 2 LAST BOM_COST PROC_VRD_VCCIN_CPU0
J 0
(-7600 2025);
PAINT MONO (-7600 2025);
DISPLAY INVISIBLE (-7600 2025);
FORCEPROP 2 LAST ROOM PVSA_CPU1_VSENSE_VR
J 0
(-7925 2050);
PAINT ORANGE (-7925 2050);
DISPLAY INVISIBLE (-7925 2050);
FORCEPROP 1 LAST OFFPAGE TRUE
J 0
(-7075 1850);
DISPLAY 0.893617 (-7075 1850);
PAINT GREEN (-7075 1850);
DISPLAY INVISIBLE (-7075 1850);
FORCEPROP 1 LAST COMMENT_BODY TRUE
J 0
(-7275 1875);
DISPLAY 0.893617 (-7275 1875);
PAINT GREEN (-7275 1875);
DISPLAY INVISIBLE (-7275 1875);
FORCEADD OFFPAGE..1
(-7425 1500);
FORCEPROP 2 LAST $XR0 206 
J 0
(-7677 1500);
DISPLAY 0.638298 (-7677 1500);
PAINT MONO (-7677 1500);
FORCEPROP 2 LAST ROOM PVSA_CPU1_VSENSE_VR
J 0
(-7950 1575);
PAINT ORANGE (-7950 1575);
DISPLAY INVISIBLE (-7950 1575);
FORCEPROP 2 LAST PATH I41
J 0
(-7660 1535);
DISPLAY 1.021277 (-7660 1535);
PAINT ORANGE (-7660 1535);
DISPLAY INVISIBLE (-7660 1535);
FORCEPROP 2 LAST CDS_LIB mstr_standard
J 0
(-7425 1500);
PAINT ORANGE (-7425 1500);
DISPLAY INVISIBLE (-7425 1500);
FORCEPROP 2 LAST BOM_COST PROC_VRD_VCCIN_CPU0
J 0
(-7625 1550);
PAINT MONO (-7625 1550);
DISPLAY INVISIBLE (-7625 1550);
FORCEPROP 1 LAST OFFPAGE TRUE
J 0
(-7100 1375);
DISPLAY 0.893617 (-7100 1375);
PAINT GREEN (-7100 1375);
DISPLAY INVISIBLE (-7100 1375);
FORCEPROP 1 LAST COMMENT_BODY TRUE
J 0
(-7300 1400);
DISPLAY 0.893617 (-7300 1400);
PAINT GREEN (-7300 1400);
DISPLAY INVISIBLE (-7300 1400);
FORCEADD P5V_STBY..1
(-4825 4575);
FORCEPROP 3 LASTPIN (-4825 4525) SIG_NAME P5V_STBY\g
J 0
(-4815 4535);
DISPLAY 0.659574 (-4815 4535);
PAINT MONO (-4815 4535);
DISPLAY INVISIBLE (-4815 4535);
FORCEPROP 1 LAST VOLTAGE 5.0V
J 0
(-4870 4532);
DISPLAY 0.340426 (-4870 4532);
PAINT SKYBLUE (-4870 4532);
DISPLAY INVISIBLE (-4870 4532);
FORCEPROP 1 LAST PATH I42
J 0
(-4780 4577);
DISPLAY 0.340426 (-4780 4577);
PAINT GREEN (-4780 4577);
DISPLAY INVISIBLE (-4780 4577);
FORCEPROP 2 LAST CDS_LIB mstr_symbols
J 0
(-4825 4575);
PAINT ORANGE (-4825 4575);
DISPLAY INVISIBLE (-4825 4575);
FORCEPROP 1 LAST SIZE 1B
J 0
(-4780 4597);
DISPLAY 0.340426 (-4780 4597);
PAINT GREEN (-4780 4597);
DISPLAY INVISIBLE (-4780 4597);
FORCEPROP 1 LAST BODY_TYPE PLUMBING
J 0
(-4870 4532);
DISPLAY 0.340426 (-4870 4532);
PAINT GREEN (-4870 4532);
DISPLAY INVISIBLE (-4870 4532);
FORCEPROP 1 LAST HDL_POWER P5V_STBY
J 0
(-5125 4450);
DISPLAY 0.872340 (-5125 4450);
PAINT ORANGE (-5125 4450);
DISPLAY INVISIBLE (-5125 4450);
FORCEADD CAP_A..1
(-1000 3100);
FORCEPROP 1 LAST PART_NUMBER E15431-004
J 0
(-950 3000);
DISPLAY 0.617021 (-950 3000);
PAINT BLUE (-950 3000);
FORCEPROP 1 LAST PACK_TYPE 0603V
J 0
(-950 2950);
DISPLAY 0.617021 (-950 2950);
PAINT SKYBLUE (-950 2950);
FORCEPROP 1 LAST MATERIAL X6S
J 0
(-950 3050);
DISPLAY 0.617021 (-950 3050);
PAINT SKYBLUE (-950 3050);
FORCEPROP 1 LAST VOLTAGE 4V
J 0
(-950 3150);
DISPLAY 0.617021 (-950 3150);
PAINT SKYBLUE (-950 3150);
FORCEPROP 1 LASTPIN (-1000 3000) $PN 2
J 0
(-990 2980);
DISPLAY 0.617021 (-990 2980);
PAINT ORANGE (-990 2980);
FORCEPROP 1 LASTPIN (-1000 3200) $PN 1
J 0
(-990 3180);
DISPLAY 0.617021 (-990 3180);
PAINT ORANGE (-990 3180);
FORCEPROP 1 LAST TOLERANCE 20%
J 0
(-950 3100);
DISPLAY 0.617021 (-950 3100);
PAINT SKYBLUE (-950 3100);
FORCEPROP 1 LAST VALUE 22.0UF
J 0
(-950 3200);
DISPLAY 0.617021 (-950 3200);
PAINT SKYBLUE (-950 3200);
FORCEPROP 1 LAST LOCATION C9N22
J 0
(-950 3250);
DISPLAY 0.617021 (-950 3250);
PAINT AQUA (-950 3250);
FORCEPROP 0 LAST GROUP PWR_MLCC_CAP
J 0
(-944 2862);
DISPLAY 0.638298 (-944 2862);
PAINT BROWN (-944 2862);
DISPLAY BOTH (-944 2862);
FORCEPROP 2 LAST CDS_LIB dev_discrete
J 0
(-1000 3100);
PAINT ORANGE (-1000 3100);
DISPLAY INVISIBLE (-1000 3100);
FORCEPROP 1 LAST PATH I44
J 0
(-950 3250);
DISPLAY 0.978723 (-950 3250);
PAINT WHITE (-950 3250);
DISPLAY INVISIBLE (-950 3250);
FORCEPROP 2 LAST SEC 1
J 0
(-950 3300);
DISPLAY 0.680851 (-950 3300);
PAINT MONO (-950 3300);
DISPLAY INVISIBLE (-950 3300);
FORCEPROP 2 LAST SEC_TYPE 0603V
J 0
(-950 3300);
DISPLAY 1.021277 (-950 3300);
PAINT ORANGE (-950 3300);
DISPLAY INVISIBLE (-950 3300);
FORCEPROP 2 LAST CDS_SEC 1
J 0
(-950 3250);
PAINT ORANGE (-950 3250);
DISPLAY INVISIBLE (-950 3250);
FORCEPROP 2 LAST CDS_LOCATION C9N22
J 0
(-950 3200);
DISPLAY 0.617021 (-950 3200);
PAINT AQUA (-950 3200);
DISPLAY INVISIBLE (-950 3200);
FORCEADD RES..2
(-650 3100);
FORCEPROP 1 LAST PART_NUMBER G21796-208
J 0
(-610 2975);
DISPLAY 0.617021 (-610 2975);
PAINT BLUE (-610 2975);
FORCEPROP 1 LAST PACK_TYPE 0402
J 0
(-610 2925);
DISPLAY 0.617021 (-610 2925);
PAINT SKYBLUE (-610 2925);
FORCEPROP 1 LAST LOCATION R9N4
J 0
(-605 3225);
DISPLAY 0.617021 (-605 3225);
PAINT AQUA (-605 3225);
FORCEPROP 1 LAST VALUE 51.1
J 0
(-605 3175);
DISPLAY 0.617021 (-605 3175);
PAINT SKYBLUE (-605 3175);
FORCEPROP 1 LASTPIN (-650 3200) $PN 1
J 0
(-645 3162);
DISPLAY 0.787234 (-645 3162);
PAINT ORANGE (-645 3162);
FORCEPROP 1 LASTPIN (-650 3000) $PN 2
J 0
(-645 3010);
DISPLAY 0.787234 (-645 3010);
PAINT ORANGE (-645 3010);
FORCEPROP 1 LAST WATTAGE 1/16W
J 0
(-610 3075);
DISPLAY 0.617021 (-610 3075);
PAINT SKYBLUE (-610 3075);
FORCEPROP 1 LAST MATERIAL CHIP
J 0
(-610 3025);
DISPLAY 0.617021 (-610 3025);
PAINT SKYBLUE (-610 3025);
FORCEPROP 1 LAST TOLERANCE 1.0%
J 0
(-605 3125);
DISPLAY 0.617021 (-605 3125);
PAINT SKYBLUE (-605 3125);
FORCEPROP 1 LAST PATH I45
J 0
(-600 3275);
DISPLAY 0.978723 (-600 3275);
PAINT WHITE (-600 3275);
DISPLAY INVISIBLE (-600 3275);
FORCEPROP 2 LAST CDS_LOCATION R9N4
J 0
(-605 3225);
DISPLAY 0.617021 (-605 3225);
PAINT AQUA (-605 3225);
DISPLAY INVISIBLE (-605 3225);
FORCEPROP 2 LAST CDS_LIB mstr_discrete
J 0
(-650 3100);
PAINT ORANGE (-650 3100);
DISPLAY INVISIBLE (-650 3100);
FORCEPROP 2 LAST SEC 1
J 0
(-600 3325);
DISPLAY 0.680851 (-600 3325);
PAINT MONO (-600 3325);
DISPLAY INVISIBLE (-600 3325);
FORCEPROP 2 LAST SEC_TYPE 0402
J 0
(-600 3325);
DISPLAY 1.021277 (-600 3325);
PAINT ORANGE (-600 3325);
DISPLAY INVISIBLE (-600 3325);
FORCEADD PVSA_CPU1..1
(-4575 2500);
FORCEPROP 3 LASTPIN (-4575 2450) SIG_NAME PVSA_CPU1\g
J 0
(-4565 2460);
DISPLAY 0.659574 (-4565 2460);
PAINT MONO (-4565 2460);
DISPLAY INVISIBLE (-4565 2460);
FORCEPROP 1 LAST VOLTAGE 1.1V
J 0
(-4620 2457);
DISPLAY 0.340426 (-4620 2457);
PAINT SKYBLUE (-4620 2457);
DISPLAY INVISIBLE (-4620 2457);
FORCEPROP 2 LAST CDS_LIB mstr_symbols
J 0
(-4575 2500);
PAINT ORANGE (-4575 2500);
DISPLAY INVISIBLE (-4575 2500);
FORCEPROP 2 LAST BOM_COST PROC_VRD_VCCIN_CPU0
J 0
(-4575 2600);
DISPLAY 1.446809 (-4575 2600);
PAINT MONO (-4575 2600);
DISPLAY INVISIBLE (-4575 2600);
FORCEPROP 1 LAST PATH I46
J 0
(-4525 2525);
DISPLAY 0.872340 (-4525 2525);
PAINT AQUA (-4525 2525);
DISPLAY INVISIBLE (-4525 2525);
FORCEPROP 2 LAST ROOM PVSA_CPU1_PWR_VR
J 0
(-4575 2600);
DISPLAY 1.936170 (-4575 2600);
PAINT ORANGE (-4575 2600);
DISPLAY INVISIBLE (-4575 2600);
FORCEPROP 1 LAST BODY_TYPE PLUMBING
J 0
(-4620 2457);
DISPLAY 0.340426 (-4620 2457);
PAINT GREEN (-4620 2457);
DISPLAY INVISIBLE (-4620 2457);
FORCEPROP 1 LAST HDL_POWER PVSA_CPU1
J 1
(-4575 2550);
DISPLAY 0.872340 (-4575 2550);
PAINT GREEN (-4575 2550);
DISPLAY INVISIBLE (-4575 2550);
FORCEADD PVSA_CPU1..1
(-1900 1700);
FORCEPROP 3 LASTPIN (-1900 1650) SIG_NAME PVSA_CPU1\g
J 0
(-1890 1660);
DISPLAY 0.659574 (-1890 1660);
PAINT MONO (-1890 1660);
DISPLAY INVISIBLE (-1890 1660);
FORCEPROP 1 LAST PATH I47
J 0
(-1850 1725);
DISPLAY 0.872340 (-1850 1725);
PAINT AQUA (-1850 1725);
DISPLAY INVISIBLE (-1850 1725);
FORCEPROP 2 LAST BOM_COST PROC_VRD_VCCIN_CPU0
J 0
(-1900 1800);
DISPLAY 1.446809 (-1900 1800);
PAINT MONO (-1900 1800);
DISPLAY INVISIBLE (-1900 1800);
FORCEPROP 2 LAST ROOM PVSA_CPU1_PWR_VR
J 0
(-1900 1800);
DISPLAY 1.936170 (-1900 1800);
PAINT ORANGE (-1900 1800);
DISPLAY INVISIBLE (-1900 1800);
FORCEPROP 2 LAST CDS_LIB mstr_symbols
J 0
(-1900 1700);
PAINT ORANGE (-1900 1700);
DISPLAY INVISIBLE (-1900 1700);
FORCEPROP 1 LAST VOLTAGE 1.1V
J 0
(-1945 1657);
DISPLAY 0.340426 (-1945 1657);
PAINT SKYBLUE (-1945 1657);
DISPLAY INVISIBLE (-1945 1657);
FORCEPROP 1 LAST BODY_TYPE PLUMBING
J 0
(-1945 1657);
DISPLAY 0.340426 (-1945 1657);
PAINT GREEN (-1945 1657);
DISPLAY INVISIBLE (-1945 1657);
FORCEPROP 1 LAST HDL_POWER PVSA_CPU1
J 1
(-1900 1750);
DISPLAY 0.872340 (-1900 1750);
PAINT GREEN (-1900 1750);
DISPLAY INVISIBLE (-1900 1750);
FORCEADD OFFPAGE..1
(-6725 3500);
FORCEPROP 2 LAST $XR0 206 
J 0
(-6977 3500);
DISPLAY 0.638298 (-6977 3500);
PAINT MONO (-6977 3500);
FORCEPROP 2 LAST PATH I50
J 0
(-6675 3575);
DISPLAY 1.021277 (-6675 3575);
PAINT ORANGE (-6675 3575);
DISPLAY INVISIBLE (-6675 3575);
FORCEPROP 2 LAST CDS_LIB mstr_standard
J 0
(-6725 3500);
PAINT ORANGE (-6725 3500);
DISPLAY INVISIBLE (-6725 3500);
FORCEPROP 2 LAST ROOM PVSA_CPU1_PWR_VR
J 0
(-7125 3575);
DISPLAY 1.936170 (-7125 3575);
PAINT ORANGE (-7125 3575);
DISPLAY INVISIBLE (-7125 3575);
FORCEPROP 2 LAST BOM_COST PROC_VRD_VCCIN_CPU0
J 0
(-6975 3550);
DISPLAY 1.446809 (-6975 3550);
PAINT MONO (-6975 3550);
DISPLAY INVISIBLE (-6975 3550);
FORCEPROP 1 LAST OFFPAGE TRUE
J 0
(-6400 3375);
DISPLAY 1.680851 (-6400 3375);
PAINT GREEN (-6400 3375);
DISPLAY INVISIBLE (-6400 3375);
FORCEPROP 1 LAST COMMENT_BODY TRUE
J 0
(-6600 3400);
DISPLAY 1.680851 (-6600 3400);
PAINT GREEN (-6600 3400);
DISPLAY INVISIBLE (-6600 3400);
FORCEADD IR354XX..1
(-3725 3600);
FORCEPROP 2 LASTPIN (-3225 3900) $PN 31
J 0
(-3215 3910);
DISPLAY 0.617021 (-3215 3910);
PAINT ORANGE (-3215 3910);
FORCEPROP 2 LASTPIN (-3225 3950) $PN 37
J 0
(-3215 3960);
DISPLAY 0.617021 (-3215 3960);
PAINT ORANGE (-3215 3960);
FORCEPROP 2 LASTPIN (-3225 4150) $PN 38
J 0
(-3215 4160);
DISPLAY 0.617021 (-3215 4160);
PAINT ORANGE (-3215 4160);
FORCEPROP 2 LASTPIN (-4225 3650) $PN 41
J 2
(-4235 3660);
DISPLAY 0.617021 (-4235 3660);
PAINT ORANGE (-4235 3660);
FORCEPROP 2 LASTPIN (-4225 3250) $PN 32
J 2
(-4235 3260);
DISPLAY 0.617021 (-4235 3260);
PAINT ORANGE (-4235 3260);
FORCEPROP 1 LAST PART_NUMBER H73684-001
J 0
(-4100 2900);
DISPLAY 0.617021 (-4100 2900);
PAINT BLUE (-4100 2900);
FORCEPROP 2 LASTPIN (-3225 3650) $PN 36
J 0
(-3215 3660);
DISPLAY 0.617021 (-3215 3660);
PAINT ORANGE (-3215 3660);
FORCEPROP 2 LASTPIN (-4225 3850) $PN 35
J 2
(-4235 3860);
DISPLAY 0.617021 (-4235 3860);
PAINT ORANGE (-4235 3860);
FORCEPROP 2 LASTPIN (-4225 3300) $PN 33
J 2
(-4235 3310);
DISPLAY 0.617021 (-4235 3310);
PAINT ORANGE (-4235 3310);
FORCEPROP 2 LASTPIN (-3225 3150) $PN 40
J 0
(-3215 3160);
DISPLAY 0.617021 (-3215 3160);
PAINT ORANGE (-3215 3160);
FORCEPROP 2 LASTPIN (-4225 3950) $PN 4
J 2
(-4235 3960);
DISPLAY 0.617021 (-4235 3960);
PAINT ORANGE (-4235 3960);
FORCEPROP 2 LASTPIN (-4225 3500) $PN 34
J 2
(-4235 3510);
DISPLAY 0.617021 (-4235 3510);
PAINT ORANGE (-4235 3510);
FORCEPROP 2 LASTPIN (-4225 3400) $PN 39
J 2
(-4235 3410);
DISPLAY 0.617021 (-4235 3410);
PAINT ORANGE (-4235 3410);
FORCEPROP 2 LASTPIN (-4225 3750) $PN 1
J 2
(-4235 3760);
DISPLAY 0.617021 (-4235 3760);
PAINT ORANGE (-4235 3760);
FORCEPROP 2 LASTPIN (-4225 3600) $PN 6
J 2
(-4235 3610);
DISPLAY 0.617021 (-4235 3610);
PAINT ORANGE (-4235 3610);
FORCEPROP 2 LASTPIN (-4225 4050) $PN 25
J 2
(-4235 4060);
DISPLAY 0.617021 (-4235 4060);
PAINT ORANGE (-4235 4060);
FORCEPROP 2 LASTPIN (-4225 4150) $PN 3
J 2
(-4235 4160);
DISPLAY 0.617021 (-4235 4160);
PAINT ORANGE (-4235 4160);
FORCEPROP 2 LASTPIN (-4225 4100) $PN 30
J 2
(-4235 4110);
DISPLAY 0.617021 (-4235 4110);
PAINT ORANGE (-4235 4110);
FORCEPROP 1 LAST MATERIAL IC
J 0
(-4175 4350);
DISPLAY 0.617021 (-4175 4350);
PAINT SKYBLUE (-4175 4350);
FORCEPROP 1 LAST LOCATION EU1C1
J 0
(-4175 4400);
DISPLAY 0.617021 (-4175 4400);
PAINT AQUA (-4175 4400);
FORCEPROP 2 LASTPIN (-3225 3050) $PN 5
J 0
(-3215 3060);
DISPLAY 0.617021 (-3215 3060);
PAINT ORANGE (-3215 3060);
FORCEPROP 2 LASTPIN (-3225 3200) $PN 2
J 0
(-3215 3210);
DISPLAY 0.617021 (-3215 3210);
PAINT ORANGE (-3215 3210);
FORCEPROP 2 LASTPIN (-3225 3100) $PN 7
J 0
(-3215 3110);
DISPLAY 0.617021 (-3215 3110);
PAINT ORANGE (-3215 3110);
FORCEPROP 2 LASTPIN (-3225 3300) $PN 10
J 0
(-3215 3310);
DISPLAY 0.617021 (-3215 3310);
PAINT ORANGE (-3215 3310);
FORCEPROP 2 LAST CDS_LOCATION EU1C1
J 0
(-4175 4400);
PAINT GREEN (-4175 4400);
DISPLAY INVISIBLE (-4175 4400);
FORCEPROP 2 LAST SEC 1
J 0
(-4175 4450);
DISPLAY 0.680851 (-4175 4450);
PAINT MONO (-4175 4450);
DISPLAY INVISIBLE (-4175 4450);
FORCEPROP 2 LAST SEC_TYPE SM
J 0
(-4175 4450);
DISPLAY 1.021277 (-4175 4450);
PAINT ORANGE (-4175 4450);
DISPLAY INVISIBLE (-4175 4450);
FORCEPROP 1 LAST PACK_TYPE SM
J 0
(-4175 4450);
PAINT SKYBLUE (-4175 4450);
DISPLAY INVISIBLE (-4175 4450);
FORCEPROP 2 LAST CDS_LIB mstr_discrete
J 0
(-3725 3600);
PAINT ORANGE (-3725 3600);
DISPLAY INVISIBLE (-3725 3600);
FORCEPROP 1 LAST PATH I51
J 0
(-3725 4350);
PAINT GREEN (-3725 4350);
DISPLAY INVISIBLE (-3725 4350);
FORCEPROP 1 LAST VALUE IR35412
J 1
(-3725 4225);
DISPLAY 0.617021 (-3725 4225);
PAINT SKYBLUE (-3725 4225);
DISPLAY INVISIBLE (-3725 4225);
FORCEADD RES..2
(-1450 3775);
FORCEPROP 1 LAST PACK_TYPE 0402
J 0
(-1410 3600);
DISPLAY 0.617021 (-1410 3600);
PAINT SKYBLUE (-1410 3600);
FORCEPROP 1 LAST PART_NUMBER G21796-187
J 0
(-1410 3650);
DISPLAY 0.617021 (-1410 3650);
PAINT BLUE (-1410 3650);
FORCEPROP 1 LAST MATERIAL EMPTY
J 0
(-1410 3700);
DISPLAY 0.617021 (-1410 3700);
PAINT RED (-1410 3700);
FORCEPROP 1 LAST WATTAGE 1/16W
J 0
(-1410 3750);
DISPLAY 0.617021 (-1410 3750);
PAINT SKYBLUE (-1410 3750);
FORCEPROP 1 LAST TOLERANCE 1%
J 0
(-1405 3800);
DISPLAY 0.617021 (-1405 3800);
PAINT SKYBLUE (-1405 3800);
FORCEPROP 1 LAST VALUE 68.1K
J 0
(-1405 3850);
DISPLAY 0.617021 (-1405 3850);
PAINT SKYBLUE (-1405 3850);
FORCEPROP 1 LASTPIN (-1450 3675) $PN 2
J 0
(-1445 3685);
DISPLAY 0.617021 (-1445 3685);
PAINT ORANGE (-1445 3685);
FORCEPROP 1 LASTPIN (-1450 3875) $PN 1
J 0
(-1445 3837);
DISPLAY 0.617021 (-1445 3837);
PAINT ORANGE (-1445 3837);
FORCEPROP 1 LAST LOCATION R1C37
J 0
(-1405 3900);
DISPLAY 0.617021 (-1405 3900);
PAINT AQUA (-1405 3900);
FORCEPROP 2 LAST CDS_LIB mstr_discrete
J 0
(-1450 3775);
PAINT ORANGE (-1450 3775);
DISPLAY INVISIBLE (-1450 3775);
FORCEPROP 2 LAST CDS_SEC 1
J 0
(-1400 4000);
PAINT MONO (-1400 4000);
DISPLAY INVISIBLE (-1400 4000);
FORCEPROP 2 LAST $SEC 1
J 0
(-1400 4000);
PAINT MONO (-1400 4000);
DISPLAY INVISIBLE (-1400 4000);
FORCEPROP 1 LAST PATH I52
J 0
(-1400 3950);
DISPLAY 0.978723 (-1400 3950);
PAINT WHITE (-1400 3950);
DISPLAY INVISIBLE (-1400 3950);
FORCEADD GND..1
(-1450 3600);
FORCEPROP 3 LASTPIN (-1450 3650) SIG_NAME GND\g
J 0
(-1440 3660);
DISPLAY 0.659574 (-1440 3660);
PAINT MONO (-1440 3660);
DISPLAY INVISIBLE (-1440 3660);
FORCEPROP 2 LAST ROOM PVSA_CPU1_PWR_VR
J 0
(-2000 3675);
DISPLAY 1.936170 (-2000 3675);
PAINT ORANGE (-2000 3675);
DISPLAY INVISIBLE (-2000 3675);
FORCEPROP 2 LAST BOM_COST PROC_VRD_VCCIN_CPU0
J 0
(-1825 3675);
DISPLAY 1.446809 (-1825 3675);
PAINT MONO (-1825 3675);
DISPLAY INVISIBLE (-1825 3675);
FORCEPROP 1 LAST PATH I53
J 0
(-1375 3600);
DISPLAY 0.872340 (-1375 3600);
PAINT AQUA (-1375 3600);
DISPLAY INVISIBLE (-1375 3600);
FORCEPROP 2 LAST CDS_LIB mstr_symbols
J 0
(-1450 3600);
PAINT ORANGE (-1450 3600);
DISPLAY INVISIBLE (-1450 3600);
FORCEPROP 1 LAST SIZE 1B
J 0
(-1375 3550);
DISPLAY 1.723404 (-1375 3550);
PAINT GREEN (-1375 3550);
DISPLAY INVISIBLE (-1375 3550);
FORCEPROP 1 LAST VOLTAGE 0
J 0
(-1450 3600);
PAINT SKYBLUE (-1450 3600);
DISPLAY INVISIBLE (-1450 3600);
FORCEPROP 1 LAST BODY_TYPE PLUMBING
J 0
(-1495 3557);
DISPLAY 0.340426 (-1495 3557);
PAINT GREEN (-1495 3557);
DISPLAY INVISIBLE (-1495 3557);
FORCEPROP 1 LAST HDL_POWER GND
J 0
(-1450 3750);
DISPLAY 1.723404 (-1450 3750);
PAINT GREEN (-1450 3750);
DISPLAY INVISIBLE (-1450 3750);
FORCEADD GND..1
(-4450 2850);
FORCEPROP 3 LASTPIN (-4450 2900) SIG_NAME GND\g
J 0
(-4440 2910);
DISPLAY 0.659574 (-4440 2910);
PAINT MONO (-4440 2910);
DISPLAY INVISIBLE (-4440 2910);
FORCEPROP 2 LAST ROOM PVCCIN_CPU0_PWR_VR
J 0
(-5000 2925);
DISPLAY 1.936170 (-5000 2925);
PAINT ORANGE (-5000 2925);
DISPLAY INVISIBLE (-5000 2925);
FORCEPROP 2 LAST BOM_COST PROC_VRD_VCCIN_CPU0
J 0
(-4825 2925);
DISPLAY 1.446809 (-4825 2925);
PAINT MONO (-4825 2925);
DISPLAY INVISIBLE (-4825 2925);
FORCEPROP 1 LAST SIZE 1B
J 0
(-4375 2800);
DISPLAY 1.723404 (-4375 2800);
PAINT GREEN (-4375 2800);
DISPLAY INVISIBLE (-4375 2800);
FORCEPROP 1 LAST VOLTAGE 0
J 0
(-4450 2850);
PAINT SKYBLUE (-4450 2850);
DISPLAY INVISIBLE (-4450 2850);
FORCEPROP 1 LAST PATH I54
J 0
(-4375 2850);
DISPLAY 0.872340 (-4375 2850);
PAINT AQUA (-4375 2850);
DISPLAY INVISIBLE (-4375 2850);
FORCEPROP 2 LAST CDS_LIB mstr_symbols
J 0
(-4450 2850);
PAINT MONO (-4450 2850);
DISPLAY INVISIBLE (-4450 2850);
FORCEPROP 1 LAST BODY_TYPE PLUMBING
J 0
(-4495 2807);
DISPLAY 0.340426 (-4495 2807);
PAINT GREEN (-4495 2807);
DISPLAY INVISIBLE (-4495 2807);
FORCEPROP 1 LAST HDL_POWER GND
J 0
(-4450 3000);
DISPLAY 1.723404 (-4450 3000);
PAINT GREEN (-4450 3000);
DISPLAY INVISIBLE (-4450 3000);
FORCEADD CAP_A..1
(-4450 3100);
FORCEPROP 1 LAST PART_NUMBER A36096-030
J 0
(-4400 2950);
DISPLAY 0.617021 (-4400 2950);
PAINT BLUE (-4400 2950);
FORCEPROP 1 LAST TOLERANCE 10%
J 0
(-4400 3050);
DISPLAY 0.617021 (-4400 3050);
PAINT SKYBLUE (-4400 3050);
FORCEPROP 1 LAST VOLTAGE 16V
J 0
(-4400 3100);
DISPLAY 0.617021 (-4400 3100);
PAINT SKYBLUE (-4400 3100);
FORCEPROP 1 LAST VALUE 0.1UF
J 0
(-4400 3150);
DISPLAY 0.617021 (-4400 3150);
PAINT SKYBLUE (-4400 3150);
FORCEPROP 1 LAST LOCATION CT57
J 0
(-4400 3200);
DISPLAY 0.617021 (-4400 3200);
PAINT AQUA (-4400 3200);
FORCEPROP 1 LASTPIN (-4450 3200) $PN 1
J 0
(-4440 3180);
DISPLAY 0.787234 (-4440 3180);
PAINT ORANGE (-4440 3180);
FORCEPROP 1 LAST PACK_TYPE 0402V
J 0
(-4400 2900);
DISPLAY 0.617021 (-4400 2900);
PAINT SKYBLUE (-4400 2900);
FORCEPROP 0 LAST POP NOPOP
J 0
(-4700 3050);
DISPLAY 1.021277 (-4700 3050);
PAINT RED (-4700 3050);
FORCEPROP 1 LASTPIN (-4450 3000) $PN 2
J 0
(-4440 2980);
DISPLAY 0.787234 (-4440 2980);
PAINT ORANGE (-4440 2980);
FORCEPROP 1 LAST MATERIAL X7R
J 0
(-4400 3000);
DISPLAY 0.617021 (-4400 3000);
PAINT SKYBLUE (-4400 3000);
FORCEPROP 2 LAST SEC_TYPE 0402V
J 0
(-4400 3300);
DISPLAY 1.021277 (-4400 3300);
PAINT ORANGE (-4400 3300);
DISPLAY INVISIBLE (-4400 3300);
FORCEPROP 0 LAST SEC 1
J 0
(-4450 3225);
DISPLAY 0.680851 (-4450 3225);
PAINT MONO (-4450 3225);
DISPLAY INVISIBLE (-4450 3225);
FORCEPROP 2 LAST ROOM PVCCIN_CPU0_PWR_VR
J 0
(-4400 3250);
DISPLAY 1.361702 (-4400 3250);
PAINT ORANGE (-4400 3250);
DISPLAY INVISIBLE (-4400 3250);
FORCEPROP 1 LAST PATH I55
J 0
(-4400 3250);
DISPLAY 0.978723 (-4400 3250);
PAINT WHITE (-4400 3250);
DISPLAY INVISIBLE (-4400 3250);
FORCEPROP 2 LAST CDS_LIB dev_discrete
J 0
(-4450 3100);
PAINT MONO (-4450 3100);
DISPLAY INVISIBLE (-4450 3100);
FORCEADD GND..1
(-2500 2600);
FORCEPROP 3 LASTPIN (-2500 2650) SIG_NAME GND\g
J 0
(-2490 2660);
DISPLAY 0.659574 (-2490 2660);
PAINT MONO (-2490 2660);
DISPLAY INVISIBLE (-2490 2660);
FORCEPROP 1 LAST SIZE 1B
J 0
(-2425 2550);
DISPLAY 1.723404 (-2425 2550);
PAINT GREEN (-2425 2550);
DISPLAY INVISIBLE (-2425 2550);
FORCEPROP 1 LAST VOLTAGE 0
J 0
(-2500 2600);
PAINT SKYBLUE (-2500 2600);
DISPLAY INVISIBLE (-2500 2600);
FORCEPROP 2 LAST BOM_COST PROC_VRD_VCCIN_CPU0
J 0
(-2875 2675);
DISPLAY 1.446809 (-2875 2675);
PAINT MONO (-2875 2675);
DISPLAY INVISIBLE (-2875 2675);
FORCEPROP 2 LAST ROOM PVCCIN_CPU0_PWR_VR
J 0
(-3050 2675);
DISPLAY 1.936170 (-3050 2675);
PAINT ORANGE (-3050 2675);
DISPLAY INVISIBLE (-3050 2675);
FORCEPROP 1 LAST PATH I58
J 0
(-2425 2600);
DISPLAY 0.872340 (-2425 2600);
PAINT AQUA (-2425 2600);
DISPLAY INVISIBLE (-2425 2600);
FORCEPROP 2 LAST CDS_LIB mstr_symbols
J 0
(-2500 2600);
PAINT MONO (-2500 2600);
DISPLAY INVISIBLE (-2500 2600);
FORCEPROP 1 LAST BODY_TYPE PLUMBING
J 0
(-2545 2557);
DISPLAY 0.340426 (-2545 2557);
PAINT GREEN (-2545 2557);
DISPLAY INVISIBLE (-2545 2557);
FORCEPROP 1 LAST HDL_POWER GND
J 0
(-2500 2750);
DISPLAY 1.723404 (-2500 2750);
PAINT GREEN (-2500 2750);
DISPLAY INVISIBLE (-2500 2750);
FORCEADD OFFPAGE..2
(-2125 3800);
FORCEPROP 2 LAST $XR0 206 
J 0
(-1936 3800);
DISPLAY 0.638298 (-1936 3800);
PAINT MONO (-1936 3800);
FORCEPROP 2 LAST ROOM PVSA_CPU1_PWR_VR
J 0
(-2525 3875);
DISPLAY 1.936170 (-2525 3875);
PAINT ORANGE (-2525 3875);
DISPLAY INVISIBLE (-2525 3875);
FORCEPROP 2 LAST CDS_LIB mstr_standard
J 0
(-2125 3800);
PAINT ORANGE (-2125 3800);
DISPLAY INVISIBLE (-2125 3800);
FORCEPROP 2 LAST PATH I6
J 0
(-1870 3850);
DISPLAY 1.021277 (-1870 3850);
PAINT ORANGE (-1870 3850);
DISPLAY INVISIBLE (-1870 3850);
FORCEPROP 2 LAST BOM_COST PROC_VRD_VCCIN_CPU0
J 0
(-1925 3850);
DISPLAY 1.446809 (-1925 3850);
PAINT MONO (-1925 3850);
DISPLAY INVISIBLE (-1925 3850);
FORCEPROP 1 LAST OFFPAGE TRUE
J 0
(-1800 3675);
DISPLAY 1.723404 (-1800 3675);
PAINT GREEN (-1800 3675);
DISPLAY INVISIBLE (-1800 3675);
FORCEPROP 1 LAST COMMENT_BODY TRUE
J 0
(-2170 3705);
DISPLAY 1.723404 (-2170 3705);
PAINT GREEN (-2170 3705);
DISPLAY INVISIBLE (-2170 3705);
FORCEADD CAP..1
(-2650 3625);
FORCEPROP 0 LAST POP NOPOP
J 0
(-2525 3600);
DISPLAY 1.021277 (-2525 3600);
PAINT RED (-2525 3600);
FORCEPROP 1 LAST VALUE 1000PF
J 0
(-2600 3675);
DISPLAY 0.617021 (-2600 3675);
PAINT SKYBLUE (-2600 3675);
FORCEPROP 1 LAST TOLERANCE 10%
J 0
(-2600 3575);
DISPLAY 0.617021 (-2600 3575);
PAINT SKYBLUE (-2600 3575);
FORCEPROP 1 LAST MATERIAL X7R
J 0
(-2600 3525);
DISPLAY 0.617021 (-2600 3525);
PAINT SKYBLUE (-2600 3525);
FORCEPROP 1 LASTPIN (-2650 3525) $PN 2
J 0
(-2640 3505);
DISPLAY 0.787234 (-2640 3505);
PAINT ORANGE (-2640 3505);
FORCEPROP 1 LAST PART_NUMBER A36096-046
J 0
(-2600 3475);
DISPLAY 0.617021 (-2600 3475);
PAINT BLUE (-2600 3475);
FORCEPROP 1 LAST VOLTAGE 50V
J 0
(-2600 3625);
DISPLAY 0.617021 (-2600 3625);
PAINT SKYBLUE (-2600 3625);
FORCEPROP 1 LAST LOCATION CT55
J 0
(-2600 3725);
DISPLAY 0.617021 (-2600 3725);
PAINT AQUA (-2600 3725);
FORCEPROP 1 LAST PACK_TYPE 0402LF
J 0
(-2600 3425);
DISPLAY 0.617021 (-2600 3425);
PAINT SKYBLUE (-2600 3425);
FORCEPROP 1 LASTPIN (-2650 3725) $PN 1
J 0
(-2640 3705);
DISPLAY 0.787234 (-2640 3705);
PAINT ORANGE (-2640 3705);
FORCEPROP 2 LAST SEC_TYPE 0402LF
J 0
(-2600 3825);
DISPLAY 1.021277 (-2600 3825);
PAINT ORANGE (-2600 3825);
DISPLAY INVISIBLE (-2600 3825);
FORCEPROP 0 LAST SEC 1
J 0
(-2600 3775);
DISPLAY 0.680851 (-2600 3775);
PAINT MONO (-2600 3775);
DISPLAY INVISIBLE (-2600 3775);
FORCEPROP 2 LAST CDS_LIB mstr_discrete
J 0
(-2650 3625);
PAINT MONO (-2650 3625);
DISPLAY INVISIBLE (-2650 3625);
FORCEPROP 1 LAST PATH I60
J 0
(-2600 3775);
DISPLAY 0.978723 (-2600 3775);
PAINT WHITE (-2600 3775);
DISPLAY INVISIBLE (-2600 3775);
FORCEPROP 0 LAST ROOM VDDQ_KLM_PWR_VR
J 0
(-2600 3825);
DISPLAY 1.021277 (-2600 3825);
PAINT ORANGE (-2600 3825);
DISPLAY INVISIBLE (-2600 3825);
FORCEADD GND..1
(-2650 3425);
FORCEPROP 3 LASTPIN (-2650 3475) SIG_NAME GND\g
J 0
(-2640 3485);
DISPLAY 0.659574 (-2640 3485);
PAINT MONO (-2640 3485);
DISPLAY INVISIBLE (-2640 3485);
FORCEPROP 1 LAST SIZE 1B
J 0
(-2575 3375);
DISPLAY 1.170213 (-2575 3375);
PAINT AQUA (-2575 3375);
DISPLAY INVISIBLE (-2575 3375);
FORCEPROP 1 LAST VOLTAGE 0
J 0
(-2650 3425);
PAINT SKYBLUE (-2650 3425);
DISPLAY INVISIBLE (-2650 3425);
FORCEPROP 2 LAST ROOM VDDQ_KLM_PWR_VR
J 0
(-3225 3500);
DISPLAY 1.361702 (-3225 3500);
PAINT ORANGE (-3225 3500);
DISPLAY INVISIBLE (-3225 3500);
FORCEPROP 1 LAST PATH I61
J 0
(-2575 3425);
DISPLAY 0.872340 (-2575 3425);
PAINT AQUA (-2575 3425);
DISPLAY INVISIBLE (-2575 3425);
FORCEPROP 2 LAST CDS_LIB mstr_symbols
J 0
(-2650 3425);
PAINT MONO (-2650 3425);
DISPLAY INVISIBLE (-2650 3425);
FORCEPROP 1 LAST BODY_TYPE PLUMBING
J 0
(-2695 3382);
DISPLAY 0.340426 (-2695 3382);
PAINT GREEN (-2695 3382);
DISPLAY INVISIBLE (-2695 3382);
FORCEPROP 1 LAST HDL_POWER GND
J 0
(-2650 3575);
DISPLAY 1.170213 (-2650 3575);
PAINT GREEN (-2650 3575);
DISPLAY INVISIBLE (-2650 3575);
FORCEADD CAP..1
(-2500 3150);
FORCEPROP 1 LAST TOLERANCE 10%
J 0
(-2450 3100);
DISPLAY 0.617021 (-2450 3100);
PAINT SKYBLUE (-2450 3100);
FORCEPROP 1 LAST VOLTAGE 50V
J 0
(-2450 3150);
DISPLAY 0.617021 (-2450 3150);
PAINT SKYBLUE (-2450 3150);
FORCEPROP 1 LAST PART_NUMBER A36096-046
J 0
(-2300 3225);
DISPLAY 0.617021 (-2300 3225);
PAINT BLUE (-2300 3225);
FORCEPROP 1 LAST VALUE 1000PF
J 0
(-2450 3200);
DISPLAY 0.617021 (-2450 3200);
PAINT SKYBLUE (-2450 3200);
FORCEPROP 1 LASTPIN (-2500 3250) $PN 1
J 0
(-2490 3230);
DISPLAY 0.787234 (-2490 3230);
PAINT ORANGE (-2490 3230);
FORCEPROP 1 LAST PACK_TYPE 0402LF
J 0
(-2300 3100);
DISPLAY 0.617021 (-2300 3100);
PAINT SKYBLUE (-2300 3100);
FORCEPROP 1 LAST MATERIAL X7R
J 0
(-2075 3225);
DISPLAY 0.617021 (-2075 3225);
PAINT SKYBLUE (-2075 3225);
FORCEPROP 1 LASTPIN (-2500 3050) $PN 2
J 0
(-2490 3030);
DISPLAY 0.787234 (-2490 3030);
PAINT ORANGE (-2490 3030);
FORCEPROP 1 LAST LOCATION CT56
J 0
(-2450 3250);
DISPLAY 0.617021 (-2450 3250);
PAINT AQUA (-2450 3250);
FORCEPROP 0 LAST POP NOPOP
J 0
(-2300 3150);
DISPLAY 0.808511 (-2300 3150);
PAINT RED (-2300 3150);
FORCEPROP 2 LAST SEC_TYPE 0402LF
J 0
(-2450 3350);
DISPLAY 1.021277 (-2450 3350);
PAINT ORANGE (-2450 3350);
DISPLAY INVISIBLE (-2450 3350);
FORCEPROP 0 LAST SEC 1
J 0
(-2450 3300);
DISPLAY 0.680851 (-2450 3300);
PAINT MONO (-2450 3300);
DISPLAY INVISIBLE (-2450 3300);
FORCEPROP 0 LAST ROOM VDDQ_KLM_PWR_VR
J 0
(-2450 3350);
DISPLAY 1.021277 (-2450 3350);
PAINT ORANGE (-2450 3350);
DISPLAY INVISIBLE (-2450 3350);
FORCEPROP 1 LAST PATH I66
J 0
(-2450 3300);
DISPLAY 0.978723 (-2450 3300);
PAINT WHITE (-2450 3300);
DISPLAY INVISIBLE (-2450 3300);
FORCEPROP 2 LAST CDS_LIB mstr_discrete
J 0
(-2500 3150);
PAINT MONO (-2500 3150);
DISPLAY INVISIBLE (-2500 3150);
FORCEADD RES..1
(-5400 3375);
FORCEPROP 1 LAST WATTAGE 1/10W
J 2
(-5025 3200);
DISPLAY 0.617021 (-5025 3200);
PAINT SKYBLUE (-5025 3200);
FORCEPROP 1 LAST MATERIAL CHIP
J 0
(-5125 3250);
DISPLAY 0.617021 (-5125 3250);
PAINT SKYBLUE (-5125 3250);
FORCEPROP 1 LAST PACK_TYPE 0603
J 0
(-5450 3200);
DISPLAY 0.617021 (-5450 3200);
PAINT SKYBLUE (-5450 3200);
FORCEPROP 1 LAST PART_NUMBER G22178-002
J 0
(-5500 3250);
DISPLAY 0.617021 (-5500 3250);
PAINT BLUE (-5500 3250);
FORCEPROP 1 LAST TOLERANCE 5.0%
J 0
(-5125 3300);
DISPLAY 0.617021 (-5125 3300);
PAINT SKYBLUE (-5125 3300);
FORCEPROP 1 LASTPIN (-5500 3375) $PN 1
J 0
(-5488 3387);
DISPLAY 0.787234 (-5488 3387);
PAINT ORANGE (-5488 3387);
FORCEPROP 1 LASTPIN (-5300 3375) $PN 2
J 0
(-5338 3387);
DISPLAY 0.787234 (-5338 3387);
PAINT ORANGE (-5338 3387);
FORCEPROP 1 LAST LOCATION RT37
J 0
(-5425 3425);
DISPLAY 0.617021 (-5425 3425);
PAINT AQUA (-5425 3425);
FORCEPROP 1 LAST VALUE 0
J 2
(-5425 3300);
DISPLAY 0.617021 (-5425 3300);
PAINT SKYBLUE (-5425 3300);
FORCEPROP 2 LAST SEC_TYPE 0603
J 0
(-5450 3575);
DISPLAY 1.021277 (-5450 3575);
PAINT ORANGE (-5450 3575);
DISPLAY INVISIBLE (-5450 3575);
FORCEPROP 0 LAST SEC 1
J 0
(-5650 3475);
DISPLAY 0.680851 (-5650 3475);
PAINT MONO (-5650 3475);
DISPLAY INVISIBLE (-5650 3475);
FORCEPROP 0 LAST ROOM NIC_SPRV
J 0
(-5300 3500);
DISPLAY 1.021277 (-5300 3500);
PAINT ORANGE (-5300 3500);
DISPLAY INVISIBLE (-5300 3500);
FORCEPROP 0 LAST BOM_COST NT_GBE_BASE
J 0
(-5300 3600);
DISPLAY 1.021277 (-5300 3600);
PAINT ORANGE (-5300 3600);
DISPLAY INVISIBLE (-5300 3600);
FORCEPROP 1 LAST PATH I68
J 0
(-5450 3525);
DISPLAY 0.978723 (-5450 3525);
PAINT WHITE (-5450 3525);
DISPLAY INVISIBLE (-5450 3525);
FORCEPROP 2 LAST CDS_LIB mstr_discrete
J 0
(-5400 3375);
PAINT MONO (-5400 3375);
DISPLAY INVISIBLE (-5400 3375);
FORCEADD PVSA_CPU1..1
(-650 3400);
FORCEPROP 3 LASTPIN (-650 3350) SIG_NAME PVSA_CPU1\g
J 0
(-640 3360);
DISPLAY 0.659574 (-640 3360);
PAINT MONO (-640 3360);
DISPLAY INVISIBLE (-640 3360);
FORCEPROP 2 LAST CDS_LIB mstr_symbols
J 0
(-650 3400);
PAINT ORANGE (-650 3400);
DISPLAY INVISIBLE (-650 3400);
FORCEPROP 1 LAST VOLTAGE 1.1V
J 0
(-695 3357);
DISPLAY 0.340426 (-695 3357);
PAINT SKYBLUE (-695 3357);
DISPLAY INVISIBLE (-695 3357);
FORCEPROP 1 LAST PATH I7
J 0
(-600 3425);
DISPLAY 0.872340 (-600 3425);
PAINT AQUA (-600 3425);
DISPLAY INVISIBLE (-600 3425);
FORCEPROP 1 LAST BODY_TYPE PLUMBING
J 0
(-695 3357);
DISPLAY 0.340426 (-695 3357);
PAINT GREEN (-695 3357);
DISPLAY INVISIBLE (-695 3357);
FORCEPROP 1 LAST HDL_POWER PVSA_CPU1
J 1
(-650 3450);
DISPLAY 0.872340 (-650 3450);
PAINT GREEN (-650 3450);
DISPLAY INVISIBLE (-650 3450);
FORCEADD RES..1
(-5725 4425);
FORCEPROP 1 LASTPIN (-5825 4425) $PN 1
J 0
(-5813 4437);
DISPLAY 0.617021 (-5813 4437);
PAINT WHITE (-5813 4437);
FORCEPROP 1 LASTPIN (-5625 4425) $PN 2
J 0
(-5663 4437);
DISPLAY 0.617021 (-5663 4437);
PAINT WHITE (-5663 4437);
FORCEPROP 1 LAST VALUE 0.0
J 0
(-5825 4325);
DISPLAY 0.617021 (-5825 4325);
PAINT SKYBLUE (-5825 4325);
FORCEPROP 1 LAST TOLERANCE 5%
J 0
(-5825 4275);
DISPLAY 0.617021 (-5825 4275);
PAINT SKYBLUE (-5825 4275);
FORCEPROP 1 LAST PART_NUMBER G21497-005
J 0
(-5825 4225);
DISPLAY 0.617021 (-5825 4225);
PAINT BLUE (-5825 4225);
FORCEPROP 1 LAST LOCATION R9N3
J 0
(-5825 4375);
DISPLAY 0.617021 (-5825 4375);
PAINT AQUA (-5825 4375);
FORCEPROP 1 LAST PACK_TYPE 0402
J 0
(-5675 4375);
DISPLAY 0.617021 (-5675 4375);
PAINT SKYBLUE (-5675 4375);
FORCEPROP 1 LAST MATERIAL CHIP
J 0
(-5675 4325);
DISPLAY 0.510638 (-5675 4325);
PAINT SKYBLUE (-5675 4325);
FORCEPROP 1 LAST WATTAGE 1/16W
J 0
(-5675 4275);
DISPLAY 0.510638 (-5675 4275);
PAINT SKYBLUE (-5675 4275);
FORCEPROP 2 LAST BOM_COST PROC_SIDEBAND
J 0
(-5725 4425);
PAINT MONO (-5725 4425);
DISPLAY INVISIBLE (-5725 4425);
FORCEPROP 2 LAST CDS_LIB mstr_discrete
J 0
(-5725 4425);
DISPLAY 1.340426 (-5725 4425);
PAINT ORANGE (-5725 4425);
DISPLAY INVISIBLE (-5725 4425);
FORCEPROP 2 LAST SEC_TYPE 0402
J 0
(-5775 4650);
DISPLAY 1.021277 (-5775 4650);
PAINT ORANGE (-5775 4650);
DISPLAY INVISIBLE (-5775 4650);
FORCEPROP 2 LAST SEC 1
J 0
(-5775 4650);
DISPLAY 0.680851 (-5775 4650);
PAINT MONO (-5775 4650);
DISPLAY INVISIBLE (-5775 4650);
FORCEPROP 2 LAST ROOM CPU0
J 0
(-5775 4575);
PAINT PEACH (-5775 4575);
DISPLAY INVISIBLE (-5775 4575);
FORCEPROP 0 LAST CDS_SEC 1
J 0
(-5425 4475);
PAINT MONO (-5425 4475);
DISPLAY INVISIBLE (-5425 4475);
FORCEPROP 1 LAST PATH I71
J 0
(-5775 4575);
DISPLAY 0.978723 (-5775 4575);
PAINT WHITE (-5775 4575);
DISPLAY INVISIBLE (-5775 4575);
FORCEPROP 2 LAST CDS_LOCATION R9N3
J 0
(-6200 4425);
DISPLAY 0.617021 (-6200 4425);
PAINT AQUA (-6200 4425);
DISPLAY INVISIBLE (-6200 4425);
FORCEADD IND-300NH-20-GP..1
R 1
(-1625 3325);
FORCEPROP 1 LAST VALUE IND-300NH-20-GP
J 0
(-1800 3250);
DISPLAY 0.617021 (-1800 3250);
PAINT GREEN (-1800 3250);
FORCEPROP 1 LAST LOCATION L1C1
J 0
(-1775 3375);
DISPLAY 0.617021 (-1775 3375);
PAINT GREEN (-1775 3375);
FORCEPROP 2 LASTPIN (-1775 3300) $PN 1
J 2
(-1785 3310);
DISPLAY 0.808511 (-1785 3310);
PAINT ORANGE (-1785 3310);
FORCEPROP 2 LASTPIN (-1475 3300) $PN 2
J 0
(-1465 3310);
DISPLAY 0.808511 (-1465 3310);
PAINT ORANGE (-1465 3310);
FORCEPROP 2 LAST ATTRIBUTE 300NH
J 0
(-1800 3200);
DISPLAY 0.638298 (-1800 3200);
PAINT GREEN (-1800 3200);
FORCEPROP 2 LAST RATED ISAT=33A@25C
J 0
(-1800 3150);
DISPLAY 0.638298 (-1800 3150);
PAINT GREEN (-1800 3150);
FORCEPROP 2 LAST PACK_SIZE DCR=0.17MOHM
J 0
(-1800 3050);
DISPLAY 0.638298 (-1800 3050);
PAINT GREEN (-1800 3050);
FORCEPROP 2 LAST TYPE IRMS=66A@DELTA_T<40C
J 0
(-1800 3100);
DISPLAY 0.638298 (-1800 3100);
PAINT GREEN (-1800 3100);
FORCEPROP 1 LAST PATH I72
R 1
J 0
(-1625 3325);
DISPLAY 0.617021 (-1625 3325);
PAINT GREEN (-1625 3325);
DISPLAY INVISIBLE (-1625 3325);
FORCEPROP 1 LAST PACK_TYPE DISCRET-GB1
R 1
J 0
(-1625 3325);
DISPLAY 0.617021 (-1625 3325);
PAINT GREEN (-1625 3325);
DISPLAY INVISIBLE (-1625 3325);
FORCEPROP 2 LAST SEC 1
J 0
(-1775 3425);
DISPLAY 0.680851 (-1775 3425);
PAINT MONO (-1775 3425);
DISPLAY INVISIBLE (-1775 3425);
FORCEPROP 2 LAST SEC_TYPE DISCRET-GB1
J 0
(-1775 3425);
DISPLAY 1.021277 (-1775 3425);
PAINT ORANGE (-1775 3425);
DISPLAY INVISIBLE (-1775 3425);
FORCEPROP 1 LAST CDS_LMAN_SYM_OUTLINE -75,100,75,-100
R 1
J 0
(-1625 3325);
DISPLAY 0.468085 (-1625 3325);
PAINT GREEN (-1625 3325);
DISPLAY INVISIBLE (-1625 3325);
FORCEPROP 2 LAST CDS_LIB w_hdl
R 1
J 0
(-1625 3325);
PAINT MONO (-1625 3325);
DISPLAY INVISIBLE (-1625 3325);
FORCEPROP 1 LAST PART_NUMBER 068.3012N.M001
R 1
J 0
(-1625 3325);
DISPLAY 0.617021 (-1625 3325);
PAINT GREEN (-1625 3325);
DISPLAY INVISIBLE (-1625 3325);
FORCEADD SC1U10V2KX-4-GP..1
(-5475 3850);
FORCEPROP 2 LAST RATED 10V
J 0
(-5350 3775);
DISPLAY 0.638298 (-5350 3775);
PAINT GREEN (-5350 3775);
FORCEPROP 2 LAST TOLERANCE 10%
J 0
(-5350 3825);
DISPLAY 0.638298 (-5350 3825);
PAINT GREEN (-5350 3825);
FORCEPROP 2 LAST PACK_SIZE 0402
J 0
(-5350 3725);
DISPLAY 0.638298 (-5350 3725);
PAINT GREEN (-5350 3725);
FORCEPROP 2 LAST ATTRIBUTE 1UF
J 0
(-5350 3875);
DISPLAY 0.638298 (-5350 3875);
PAINT GREEN (-5350 3875);
FORCEPROP 2 LASTPIN (-5475 3925) $PN 1
R 1
J 0
(-5485 3935);
DISPLAY 0.808511 (-5485 3935);
PAINT ORANGE (-5485 3935);
FORCEPROP 1 LAST VALUE SC1U10V2KX-4-GP
R 1
J 0
(-5375 3600);
DISPLAY 0.617021 (-5375 3600);
PAINT GREEN (-5375 3600);
FORCEPROP 1 LAST LOCATION C1C3
J 0
(-5350 3930);
DISPLAY 0.617021 (-5350 3930);
PAINT GREEN (-5350 3930);
FORCEPROP 2 LASTPIN (-5475 3775) $PN 2
R 1
J 2
(-5485 3765);
DISPLAY 0.808511 (-5485 3765);
PAINT ORANGE (-5485 3765);
FORCEPROP 2 LAST SEC_TYPE SMD-BCG6
J 0
(-5450 3925);
DISPLAY 1.021277 (-5450 3925);
PAINT ORANGE (-5450 3925);
DISPLAY INVISIBLE (-5450 3925);
FORCEPROP 2 LAST SEC 1
J 0
(-5450 3925);
DISPLAY 0.680851 (-5450 3925);
PAINT MONO (-5450 3925);
DISPLAY INVISIBLE (-5450 3925);
FORCEPROP 1 LAST PACK_TYPE SMD-BCG6
J 0
(-5475 3850);
DISPLAY 0.617021 (-5475 3850);
PAINT GREEN (-5475 3850);
DISPLAY INVISIBLE (-5475 3850);
FORCEPROP 1 LAST CDS_LMAN_SYM_OUTLINE -50,25,50,-25
J 0
(-5475 3850);
DISPLAY 0.468085 (-5475 3850);
PAINT GREEN (-5475 3850);
DISPLAY INVISIBLE (-5475 3850);
FORCEPROP 1 LAST PATH I73
J 0
(-5475 3850);
DISPLAY 0.617021 (-5475 3850);
PAINT GREEN (-5475 3850);
DISPLAY INVISIBLE (-5475 3850);
FORCEPROP 2 LAST CDS_LIB w_hdl
J 0
(-5475 3850);
PAINT MONO (-5475 3850);
DISPLAY INVISIBLE (-5475 3850);
FORCEPROP 1 LAST PART_NUMBER 78.10523.8FL
J 0
(-5475 3850);
DISPLAY 0.617021 (-5475 3850);
PAINT GREEN (-5475 3850);
DISPLAY INVISIBLE (-5475 3850);
FORCEADD 1R3F-GP..1
(-2500 2825);
FORCEPROP 1 LAST LOCATION RT38
J 0
(-2450 2950);
DISPLAY 0.617021 (-2450 2950);
PAINT GREEN (-2450 2950);
FORCEPROP 1 LAST VALUE 1R3F-GP
J 0
(-2450 2900);
DISPLAY 0.617021 (-2450 2900);
PAINT GREEN (-2450 2900);
FORCEPROP 2 LAST ATTRIBUTE 1 OHM
J 0
(-2450 2850);
DISPLAY 0.638298 (-2450 2850);
PAINT GREEN (-2450 2850);
FORCEPROP 2 LAST TOLERANCE 1%
J 0
(-2450 2800);
DISPLAY 0.638298 (-2450 2800);
PAINT GREEN (-2450 2800);
FORCEPROP 2 LASTPIN (-2500 2700) $PN 2
R 1
J 2
(-2510 2690);
DISPLAY 0.808511 (-2510 2690);
PAINT ORANGE (-2510 2690);
FORCEPROP 2 LASTPIN (-2500 2950) $PN 1
R 1
J 0
(-2510 2960);
DISPLAY 0.808511 (-2510 2960);
PAINT ORANGE (-2510 2960);
FORCEPROP 2 LAST RATED 1/10W
J 0
(-2450 2750);
DISPLAY 0.638298 (-2450 2750);
PAINT GREEN (-2450 2750);
FORCEPROP 0 LAST POP NOPOP
J 0
(-2450 2650);
DISPLAY 0.638298 (-2450 2650);
PAINT RED (-2450 2650);
FORCEPROP 2 LAST PACK_SIZE 0603
J 0
(-2450 2700);
DISPLAY 0.638298 (-2450 2700);
PAINT GREEN (-2450 2700);
FORCEPROP 1 LAST PACK_TYPE RCL_GP
J 0
(-2500 2825);
DISPLAY 0.617021 (-2500 2825);
PAINT GREEN (-2500 2825);
DISPLAY INVISIBLE (-2500 2825);
FORCEPROP 2 LAST SEC 1
J 0
(-2450 2925);
DISPLAY 0.680851 (-2450 2925);
PAINT MONO (-2450 2925);
DISPLAY INVISIBLE (-2450 2925);
FORCEPROP 2 LAST SEC_TYPE RCL_GP
J 0
(-2450 2925);
DISPLAY 1.021277 (-2450 2925);
PAINT ORANGE (-2450 2925);
DISPLAY INVISIBLE (-2450 2925);
FORCEPROP 1 LAST PART_NUMBER 64.1R005.55L
J 0
(-2500 2825);
DISPLAY 0.617021 (-2500 2825);
PAINT GREEN (-2500 2825);
DISPLAY INVISIBLE (-2500 2825);
FORCEPROP 2 LAST CDS_LIB w_hdl
J 0
(-2500 2825);
DISPLAY INVISIBLE (-2500 2825);
FORCEPROP 1 LAST CDS_LMAN_SYM_OUTLINE -50,75,50,-75
J 0
(-2500 2825);
DISPLAY 0.468085 (-2500 2825);
PAINT GREEN (-2500 2825);
DISPLAY INVISIBLE (-2500 2825);
FORCEPROP 1 LAST PATH I74
J 0
(-2500 2825);
DISPLAY 0.617021 (-2500 2825);
PAINT GREEN (-2500 2825);
DISPLAY INVISIBLE (-2500 2825);
FORCEADD CAP_A..1
(-1300 3100);
FORCEPROP 1 LAST PACK_TYPE 0603V
J 0
(-1250 2950);
DISPLAY 0.617021 (-1250 2950);
PAINT SKYBLUE (-1250 2950);
FORCEPROP 1 LAST PART_NUMBER E15431-004
J 0
(-1250 3000);
DISPLAY 0.617021 (-1250 3000);
PAINT BLUE (-1250 3000);
FORCEPROP 1 LAST MATERIAL X6S
J 0
(-1250 3050);
DISPLAY 0.617021 (-1250 3050);
PAINT SKYBLUE (-1250 3050);
FORCEPROP 1 LAST VOLTAGE 4V
J 0
(-1250 3150);
DISPLAY 0.617021 (-1250 3150);
PAINT SKYBLUE (-1250 3150);
FORCEPROP 1 LAST VALUE 22.0UF
J 0
(-1250 3200);
DISPLAY 0.617021 (-1250 3200);
PAINT SKYBLUE (-1250 3200);
FORCEPROP 1 LAST LOCATION C1C19
J 0
(-1250 3250);
DISPLAY 0.617021 (-1250 3250);
PAINT AQUA (-1250 3250);
FORCEPROP 1 LASTPIN (-1300 3000) $PN 2
J 0
(-1290 2980);
DISPLAY 0.617021 (-1290 2980);
PAINT ORANGE (-1290 2980);
FORCEPROP 1 LASTPIN (-1300 3200) $PN 1
J 0
(-1290 3180);
DISPLAY 0.617021 (-1290 3180);
PAINT ORANGE (-1290 3180);
FORCEPROP 1 LAST TOLERANCE 20%
J 0
(-1250 3100);
DISPLAY 0.617021 (-1250 3100);
PAINT SKYBLUE (-1250 3100);
FORCEPROP 0 LAST GROUP PWR_MLCC_CAP
J 0
(-1244 2912);
DISPLAY 0.638298 (-1244 2912);
PAINT BROWN (-1244 2912);
DISPLAY BOTH (-1244 2912);
FORCEPROP 2 LAST CDS_LIB dev_discrete
J 0
(-1300 3100);
PAINT ORANGE (-1300 3100);
DISPLAY INVISIBLE (-1300 3100);
FORCEPROP 2 LAST CDS_LOCATION C1C19
J 0
(-1250 3200);
DISPLAY 0.617021 (-1250 3200);
PAINT AQUA (-1250 3200);
DISPLAY INVISIBLE (-1250 3200);
FORCEPROP 2 LAST ROOM PVSA_CPU1_PWR_VR
J 0
(-1250 3250);
DISPLAY 1.446809 (-1250 3250);
PAINT MONO (-1250 3250);
DISPLAY INVISIBLE (-1250 3250);
FORCEPROP 2 LAST BOM_COST PROC_VRD_VCCIN_CPU0
J 0
(-1250 3250);
DISPLAY 1.446809 (-1250 3250);
PAINT MONO (-1250 3250);
DISPLAY INVISIBLE (-1250 3250);
FORCEPROP 2 LAST CDS_SEC 1
J 0
(-1250 3250);
PAINT ORANGE (-1250 3250);
DISPLAY INVISIBLE (-1250 3250);
FORCEPROP 2 LAST SEC_TYPE 0603V
J 0
(-1245 3300);
DISPLAY 1.021277 (-1245 3300);
PAINT ORANGE (-1245 3300);
DISPLAY INVISIBLE (-1245 3300);
FORCEPROP 2 LAST SEC 1
J 0
(-1245 3300);
DISPLAY 0.680851 (-1245 3300);
PAINT MONO (-1245 3300);
DISPLAY INVISIBLE (-1245 3300);
FORCEPROP 1 LAST PATH I8
J 0
(-1250 3250);
DISPLAY 0.978723 (-1250 3250);
PAINT WHITE (-1250 3250);
DISPLAY INVISIBLE (-1250 3250);
FORCEADD GND..1
(-650 2825);
FORCEPROP 3 LASTPIN (-650 2875) SIG_NAME GND\g
J 0
(-640 2885);
DISPLAY 0.659574 (-640 2885);
PAINT MONO (-640 2885);
DISPLAY INVISIBLE (-640 2885);
FORCEPROP 1 LAST SIZE 1B
J 0
(-575 2775);
DISPLAY 1.723404 (-575 2775);
PAINT GREEN (-575 2775);
DISPLAY INVISIBLE (-575 2775);
FORCEPROP 1 LAST PATH I9
J 0
(-575 2825);
DISPLAY 0.872340 (-575 2825);
PAINT AQUA (-575 2825);
DISPLAY INVISIBLE (-575 2825);
FORCEPROP 1 LAST VOLTAGE 0
J 0
(-650 2825);
PAINT SKYBLUE (-650 2825);
DISPLAY INVISIBLE (-650 2825);
FORCEPROP 2 LAST CDS_LIB mstr_symbols
J 0
(-650 2825);
PAINT ORANGE (-650 2825);
DISPLAY INVISIBLE (-650 2825);
FORCEPROP 2 LAST BOM_COST PROC_VRD_VCCIN_CPU0
J 0
(-1025 2900);
DISPLAY 1.446809 (-1025 2900);
PAINT MONO (-1025 2900);
DISPLAY INVISIBLE (-1025 2900);
FORCEPROP 2 LAST ROOM PVSA_CPU1_PWR_VR
J 0
(-1200 2900);
DISPLAY 1.936170 (-1200 2900);
PAINT ORANGE (-1200 2900);
DISPLAY INVISIBLE (-1200 2900);
FORCEPROP 1 LAST BODY_TYPE PLUMBING
J 0
(-695 2782);
DISPLAY 0.340426 (-695 2782);
PAINT GREEN (-695 2782);
DISPLAY INVISIBLE (-695 2782);
FORCEPROP 1 LAST HDL_POWER GND
J 0
(-650 2975);
DISPLAY 1.723404 (-650 2975);
PAINT GREEN (-650 2975);
DISPLAY INVISIBLE (-650 2975);
FORCEADD DNS..2
(-5945 1720);
PAINT RED (-5945 1720);
FORCEPROP 2 LAST CDS_LIB mstr_misc
J 0
(-5945 1720);
PAINT ORANGE (-5945 1720);
DISPLAY INVISIBLE (-5945 1720);
FORCEPROP 1 LAST COMMENT_BODY TRUE
R 1
J 0
(-5870 1495);
DISPLAY 0.872340 (-5870 1495);
PAINT GREEN (-5870 1495);
DISPLAY INVISIBLE (-5870 1495);
FORCEADD DESIGN_NOTE..1
(-3000 1675);
PAINT PURPLE (-3000 1675);
FORCEPROP 2 LAST ROOM PVCCIN_CPU0_VR
J 0
(-3200 1625);
PAINT MONO (-3200 1625);
DISPLAY INVISIBLE (-3200 1625);
FORCEPROP 2 LAST BOM_COST SM_CONTROLLER
J 0
(-3200 1625);
PAINT MONO (-3200 1625);
DISPLAY INVISIBLE (-3200 1625);
FORCEPROP 2 LAST CDS_LIB mstr_symbols
J 0
(-3000 1675);
PAINT ORANGE (-3000 1675);
DISPLAY INVISIBLE (-3000 1675);
FORCEPROP 1 LAST COMMENT_BODY TRUE
J 0
(-2975 1775);
DISPLAY 1.319149 (-2975 1775);
PAINT GREEN (-2975 1775);
DISPLAY INVISIBLE (-2975 1775);
FORCEADD INTEL_CORP_BPAGE..1
(0 0);
FORCEPROP 1 LAST CDS_CON_LAST_MODIFIED Fri Jun 16 17:49:16 2017
J 0
(-1425 325);
PAINT ORANGE (-1425 325);
DISPLAY INVISIBLE (-1425 325);
FORCEPROP 1 LAST CUSTOM_TXT_CDS <CURRENT_DESIGN_SHEET> OF <TOTAL_DESIGN_SHEETS>
J 0
(-500 25);
PAINT ORANGE (-500 25);
FORCEPROP 1 LAST CUSTOM_TXT_CDS <CON_LAST_MODIFIED>
J 0
(-4000 100);
PAINT ORANGE (-4000 100);
FORCEPROP 2 LAST CUSTOM_TXT_CDS <XR_PAGE_TITLE>
J 0
(-7890 5250);
DISPLAY 0.638298 (-7890 5250);
PAINT PINK (-7890 5250);
DISPLAY INVISIBLE (-7890 5250);
FORCEPROP 1 LAST SCH_TITLE VSA CPU1
J 0
(-7950 50);
DISPLAY 1.212766 (-7950 50);
PAINT ORANGE (-7950 50);
FORCEPROP 1 LAST COMMENT_BODY TRUE
J 0
(12 12);
DISPLAY 0.468085 (12 12);
PAINT GREEN (12 12);
DISPLAY INVISIBLE (12 12);
FORCEPROP 2 LAST PAGE_BORDER TRUE
J 0
(-7890 5250);
DISPLAY 0.638298 (-7890 5250);
PAINT PINK (-7890 5250);
DISPLAY INVISIBLE (-7890 5250);
FORCEPROP 2 LAST CDS_LIB mstr_symbols
J 0
(0 0);
PAINT MONO (0 0);
DISPLAY INVISIBLE (0 0);
FORCEPROP 2 LAST CDS_XR_PAGE_TITLE CR-210 : @BASEBOARD_FAB2_LIB.BASEBOARD_FAB2(SCH_1):PAGE210
J 0
(-7890 5250);
DISPLAY 0.638298 (-7890 5250);
PAINT PINK (-7890 5250);
DISPLAY INVISIBLE (-7890 5250);
FORCEADD DNS..2
(-1445 3770);
PAINT RED (-1445 3770);
FORCEPROP 2 LAST CDS_LIB mstr_misc
J 0
(-1445 3770);
PAINT ORANGE (-1445 3770);
DISPLAY INVISIBLE (-1445 3770);
FORCEPROP 1 LAST COMMENT_BODY TRUE
R 1
J 0
(-1370 3545);
DISPLAY 0.872340 (-1370 3545);
PAINT GREEN (-1370 3545);
DISPLAY INVISIBLE (-1370 3545);
WIRE 16 -1 (-1900 1125)(-1900 1150);
WIRE 16 -1 (-1900 1150)(-1350 1150);
WIRE 16 -1 (-1900 1350)(-1900 1150);
WIRE 16 -1 (-1350 1150)(-1350 1350);
WIRE 16 -1 (-3100 2950)(-3100 3050);
WIRE 16 -1 (-3100 3050)(-3100 3100);
WIRE 16 -1 (-3100 3050)(-3225 3050);
WIRE 16 -1 (-3100 3100)(-3100 3150);
WIRE 16 -1 (-3100 3100)(-3225 3100);
WIRE 16 -1 (-3100 3150)(-3100 3200);
WIRE 16 -1 (-3100 3150)(-3225 3150);
WIRE 16 -1 (-3225 3200)(-3100 3200);
WIRE 16 -1 (-6700 4050)(-6700 4200);
WIRE 16 -1 (-6700 4050)(-6625 4050);
WIRE 16 -1 (-6700 4050)(-6900 4050);
WIRE 16 -1 (-7175 4050)(-6900 4050);
WIRE 16 -1 (-6900 3950)(-6900 4050);
WIRE 16 -1 (-6625 4050)(-6375 4050);
WIRE 16 -1 (-6625 3925)(-6625 4050);
WIRE 16 -1 (-6375 4050)(-6125 4050);
WIRE 16 -1 (-6375 3925)(-6375 4050);
WIRE 16 -1 (-7175 3950)(-7175 4050);
WIRE 16 -1 (-4350 4050)(-6125 4050);
WIRE 16 -1 (-6125 3950)(-6125 4050);
WIRE 16 -1 (-4350 4050)(-4350 4100);
WIRE 16 -1 (-4225 4050)(-4350 4050);
WIRE 16 -1 (-4350 4100)(-4225 4100);
WIRE 16 -1 (-4450 1000)(-4450 1100);
WIRE 16 -1 (-4450 1100)(-5175 1100);
WIRE 16 -1 (-7175 3475)(-7175 3575);
WIRE 16 -1 (-7175 3575)(-6900 3575);
WIRE 16 -1 (-7175 3750)(-7175 3575);
WIRE 16 -1 (-6625 3575)(-6900 3575);
WIRE 16 -1 (-6900 3750)(-6900 3575);
WIRE 16 -1 (-6625 3575)(-6375 3575);
WIRE 16 -1 (-6625 3725)(-6625 3575);
WIRE 16 -1 (-6375 3575)(-6125 3575);
WIRE 16 -1 (-6375 3725)(-6375 3575);
WIRE 16 -1 (-6125 3575)(-5875 3575);
WIRE 16 -1 (-6125 3750)(-6125 3575);
WIRE 16 -1 (-5875 3575)(-5475 3575);
WIRE 16 -1 (-5875 3725)(-5875 3575);
WIRE 16 -1 (-5200 3575)(-5475 3575);
WIRE 16 -1 (-5475 3775)(-5475 3575);
WIRE 16 -1 (-5200 3750)(-5200 3575);
WIRE 16 -1 (-4825 4425)(-4825 4525);
WIRE 16 -1 (-4825 4425)(-4550 4425);
WIRE 16 -1 (-4825 4425)(-5200 4425);
WIRE 16 -1 (-5200 4425)(-5475 4425);
WIRE 16 -1 (-5200 3950)(-5200 4425);
WIRE 16 -1 (-4550 4425)(-4550 3950);
WIRE 16 -1 (-4550 3950)(-4550 3850);
WIRE 16 -1 (-4550 3950)(-4225 3950);
WIRE 16 -1 (-5475 3925)(-5475 4425);
WIRE 16 -1 (-5625 4425)(-5475 4425);
WIRE 16 -1 (-4550 3850)(-4225 3850);
WIRE 16 -1 (-4575 2325)(-4575 2450);
WIRE 16 -1 (-5200 2325)(-4575 2325);
WIRE 16 -1 (-1900 1600)(-1900 1650);
WIRE 16 -1 (-1900 1600)(-1350 1600);
WIRE 16 -1 (-1900 1550)(-1900 1600);
WIRE 16 -1 (-1350 1550)(-1350 1600);
WIRE 16 -1 (-1450 3675)(-1450 3650);
WIRE 16 -1 (-4450 3000)(-4450 2900);
WIRE 16 -1 (-2500 2700)(-2500 2650);
WIRE 16 -1 (-2650 3525)(-2650 3475);
WIRE 16 -1 (-650 3350)(-650 3300);
WIRE 16 -1 (-650 3300)(-1000 3300);
WIRE 16 -1 (-650 3200)(-650 3300);
WIRE 16 -1 (-1300 3300)(-1000 3300);
WIRE 16 -1 (-1000 3200)(-1000 3300);
WIRE 16 -1 (-1400 3300)(-1300 3300);
WIRE 16 -1 (-1300 3200)(-1300 3300);
WIRE 16 -1 (-1400 2375)(-1400 3300);
WIRE 16 -1 (-1475 3300)(-1400 3300);
WIRE 16 -1 (-4350 2375)(-1400 2375);
WIRE 16 -1 (-4350 3750)(-4350 2375);
WIRE 16 -1 (-4225 3750)(-4350 3750);
WIRE 16 -1 (-650 2875)(-650 2900);
WIRE 16 -1 (-650 2900)(-1000 2900);
WIRE 16 -1 (-650 3000)(-650 2900);
WIRE 16 -1 (-1000 2900)(-1300 2900);
WIRE 16 -1 (-1000 3000)(-1000 2900);
WIRE 16 -1 (-1300 2900)(-1300 3000);
WIRE 3 2175 (-4725 2825)(-4125 2825);
WIRE 3 2175 (-4125 3350)(-4125 2825);
WIRE 3 2175 (-4725 3350)(-4725 2825);
WIRE 3 2175 (-4725 3350)(-4125 3350);
WIRE 16 2175 (-6425 3450)(-5675 3450);
WIRE 16 2175 (-5675 3450)(-5675 3025);
WIRE 16 2175 (-6425 3450)(-6425 3025);
WIRE 16 2175 (-6425 3025)(-5675 3025);
WIRE 16 -1 (-2500 3300)(-3225 3300);
FORCEPROP 0 LAST VOLTAGE 5
J 0
(-2825 3375);
DISPLAY 1.021277 (-2825 3375);
PAINT SKYBLUE (-2825 3375);
DISPLAY INVISIBLE (-2825 3375);
FORCEPROP 2 LAST SIG_NAME VR_PVSA_CPU1_PHASE_SW
J 0
(-3110 3310);
DISPLAY 0.617021 (-3110 3310);
PAINT ORANGE (-3110 3310);
FORCEPROP 2 LASTPROP $XRERR UNIQUE?
J 0
(-3350 3310);
DISPLAY 0.638298 (-3350 3310);
PAINT MONO (-3350 3310);
DISPLAY INVISIBLE (-3350 3310);
WIRE 16 -1 (-2500 3250)(-2500 3300);
WIRE 16 -1 (-1775 3300)(-2500 3300);
WIRE 16 -1 (-4225 3600)(-5000 3600);
FORCEPROP 0 LAST SIG_NAME TP_PVSA_CPU1_GL_0
J 0
(-4985 3610);
DISPLAY 0.617021 (-4985 3610);
PAINT ORANGE (-4985 3610);
FORCEPROP 2 LASTPROP $XRERR UNIQUE?
J 0
(-5240 3600);
DISPLAY 0.638298 (-5240 3600);
PAINT MONO (-5240 3600);
DISPLAY INVISIBLE (-5240 3600);
WIRE 16 -1 (-4225 3650)(-5000 3650);
FORCEPROP 0 LAST SIG_NAME TP_PVSA_CPU1_GL_1
J 0
(-4985 3660);
DISPLAY 0.617021 (-4985 3660);
PAINT ORANGE (-4985 3660);
FORCEPROP 2 LASTPROP $XRERR UNIQUE?
J 0
(-5240 3650);
DISPLAY 0.638298 (-5240 3650);
PAINT MONO (-5240 3650);
DISPLAY INVISIBLE (-5240 3650);
WIRE 16 -1 (-5875 4425)(-5825 4425);
WIRE 16 -1 (-5875 3925)(-5875 4150);
WIRE 16 -1 (-5875 4425)(-5875 4150);
WIRE 16 -1 (-5875 4150)(-4225 4150);
FORCEPROP 0 LAST VOLTAGE 5
J 0
(-5400 4225);
DISPLAY 1.021277 (-5400 4225);
PAINT SKYBLUE (-5400 4225);
DISPLAY INVISIBLE (-5400 4225);
FORCEPROP 2 LAST SIG_NAME VR_PVSA_CPU1_VCIN
J 0
(-5860 4160);
DISPLAY 0.617021 (-5860 4160);
PAINT ORANGE (-5860 4160);
FORCEPROP 2 LASTPROP $XRERR UNIQUE?
J 0
(-6100 4160);
DISPLAY 0.638298 (-6100 4160);
PAINT MONO (-6100 4160);
DISPLAY INVISIBLE (-6100 4160);
WIRE 16 -1 (-5600 1100)(-5375 1100);
WIRE 16 -1 (-5600 1100)(-5600 1475);
WIRE 16 -1 (-5600 1475)(-5375 1475);
WIRE 16 -1 (-5950 1625)(-5950 1475);
WIRE 16 -1 (-5950 1475)(-5600 1475);
WIRE 16 -1 (-6175 1475)(-5950 1475);
WIRE 16 -1 (-6175 1700)(-6175 1475);
WIRE 16 -1 (-6500 1700)(-6175 1700);
WIRE 16 -1 (-6500 1500)(-6500 1700);
WIRE 16 -1 (-7375 1500)(-6500 1500);
FORCEPROP 2 LAST SIG_NAME VSENSE_PVSA_CPU1_N
J 0
(-7370 1520);
DISPLAY 0.617021 (-7370 1520);
PAINT ORANGE (-7370 1520);
WIRE 16 -1 (-5175 1475)(-4000 1475);
FORCEPROP 2 LAST SIG_NAME VSENSE_PVSA_CPU1_SKT_VRTN
J 0
(-4945 1495);
DISPLAY 0.617021 (-4945 1495);
PAINT ORANGE (-4945 1495);
WIRE 16 -1 (-6125 3375)(-6125 3350);
WIRE 16 -1 (-5500 3375)(-6125 3375);
FORCEPROP 2 LAST SIG_NAME VR_PVSA_CPU1_BOOT
J 0
(-6114 3385);
DISPLAY 0.617021 (-6114 3385);
PAINT ORANGE (-6114 3385);
FORCEPROP 2 LASTPROP $XRERR UNIQUE?
J 0
(-6354 3385);
DISPLAY 0.638298 (-6354 3385);
PAINT MONO (-6354 3385);
DISPLAY INVISIBLE (-6354 3385);
WIRE 16 -1 (-5400 2325)(-5600 2325);
WIRE 16 -1 (-5600 1925)(-5375 1925);
WIRE 16 -1 (-5600 2325)(-5600 1925);
WIRE 16 -1 (-5950 1825)(-5950 1925);
WIRE 16 -1 (-5950 1925)(-5600 1925);
WIRE 16 -1 (-6175 1925)(-5950 1925);
WIRE 16 -1 (-6175 1775)(-6175 1925);
WIRE 16 -1 (-6500 1775)(-6175 1775);
WIRE 16 -1 (-6500 1775)(-6500 1975);
WIRE 16 -1 (-7350 1975)(-6500 1975);
FORCEPROP 2 LAST SIG_NAME VSENSE_PVSA_CPU1_P
J 0
(-7320 1995);
DISPLAY 0.617021 (-7320 1995);
PAINT ORANGE (-7320 1995);
WIRE 16 -1 (-5175 1925)(-4000 1925);
FORCEPROP 2 LAST SIG_NAME VSENSE_PVSA_CPU1_SKT_VSEN
J 0
(-4945 1945);
DISPLAY 0.617021 (-4945 1945);
PAINT ORANGE (-4945 1945);
WIRE 16 -1 (-4450 4625)(-1750 4625);
FORCEPROP 2 LAST SIG_NAME VR_PVSA_CPU1_BIREF1
J 0
(-2605 4642);
DISPLAY 0.617021 (-2605 4642);
PAINT ORANGE (-2605 4642);
WIRE 16 -1 (-4450 3200)(-4450 3400);
WIRE 16 -1 (-4225 3400)(-4450 3400);
WIRE 16 -1 (-4450 3400)(-4450 4625);
WIRE 16 -1 (-4550 3300)(-4225 3300);
WIRE 16 -1 (-4550 3375)(-4550 3300);
WIRE 16 -1 (-5300 3375)(-4550 3375);
FORCEPROP 2 LAST SIG_NAME VR_PVSA_CPU1_BOOT_R
J 0
(-5164 3385);
DISPLAY 0.617021 (-5164 3385);
PAINT ORANGE (-5164 3385);
FORCEPROP 2 LASTPROP $XRERR UNIQUE?
J 0
(-5404 3385);
DISPLAY 0.638298 (-5404 3385);
PAINT MONO (-5404 3385);
DISPLAY INVISIBLE (-5404 3385);
WIRE 16 -1 (-4550 3250)(-4225 3250);
WIRE 16 -1 (-4550 3125)(-4550 3250);
WIRE 16 -1 (-6125 3125)(-6125 3150);
WIRE 16 -1 (-6125 3125)(-4550 3125);
FORCEPROP 0 LAST VOLTAGE 5
J 0
(-5950 3200);
DISPLAY 1.021277 (-5950 3200);
PAINT SKYBLUE (-5950 3200);
DISPLAY INVISIBLE (-5950 3200);
FORCEPROP 2 LAST SIG_NAME VR_PVSA_CPU1_PHASE
J 0
(-6080 3135);
DISPLAY 0.617021 (-6080 3135);
PAINT ORANGE (-6080 3135);
FORCEPROP 2 LASTPROP $XRERR UNIQUE?
J 0
(-6320 3135);
DISPLAY 0.638298 (-6320 3135);
PAINT MONO (-6320 3135);
DISPLAY INVISIBLE (-6320 3135);
WIRE 3 2175 (-2700 3850)(-2250 3850);
WIRE 3 2175 (-2250 3850)(-2250 3375);
WIRE 3 2175 (-2700 3850)(-2700 3375);
WIRE 3 2175 (-2700 3375)(-2250 3375);
WIRE 16 -1 (-1450 3950)(-1450 3875);
WIRE 16 -1 (-3225 3950)(-1450 3950);
FORCEPROP 0 LAST SIG_NAME VR_PVSA_CPU1_OCSET
J 0
(-3085 3960);
DISPLAY 0.617021 (-3085 3960);
PAINT ORANGE (-3085 3960);
FORCEPROP 2 LASTPROP $XRERR UNIQUE?
J 0
(-3325 3960);
DISPLAY 0.638298 (-3325 3960);
PAINT MONO (-3325 3960);
DISPLAY INVISIBLE (-3325 3960);
WIRE 16 -1 (-1525 4150)(-3225 4150);
FORCEPROP 2 LAST SIG_NAME ISENSE_PVSA_CPU1_IMON
J 0
(-2879 4167);
DISPLAY 0.617021 (-2879 4167);
PAINT ORANGE (-2879 4167);
WIRE 3 682 (-3150 3900)(-3050 3900);
WIRE 3 2175 (-2575 2550)(-1850 2550);
WIRE 3 2175 (-1850 3325)(-1850 2550);
WIRE 3 2175 (-2575 3325)(-2575 2550);
WIRE 3 2175 (-2575 3325)(-1850 3325);
WIRE 16 -1 (-3150 3650)(-3225 3650);
WIRE 16 -1 (-2650 3725)(-2650 3800);
WIRE 16 -1 (-2650 3800)(-2175 3800);
WIRE 16 -1 (-3150 3800)(-3150 3650);
WIRE 16 -1 (-3150 3800)(-2650 3800);
FORCEPROP 2 LAST SIG_NAME A_TSENSE_PVSA_CPU1
J 0
(-3150 3813);
DISPLAY 0.617021 (-3150 3813);
PAINT ORANGE (-3150 3813);
WIRE 3 2175 (-5600 3475)(-5175 3475);
WIRE 3 2175 (-5175 3475)(-5175 3150);
WIRE 3 2175 (-5600 3475)(-5600 3150);
WIRE 3 2175 (-5600 3150)(-5175 3150);
WIRE 16 -1 (-6675 3500)(-4225 3500);
FORCEPROP 2 LAST SIG_NAME VR_PVSA_CPU1_PWM
J 0
(-6608 3510);
DISPLAY 0.617021 (-6608 3510);
PAINT ORANGE (-6608 3510);
WIRE 3 682 (-5525 3975)(-5525 3700);
WIRE 3 682 (-5425 3975)(-5525 3975);
WIRE 3 682 (-5525 3700)(-5425 3700);
WIRE 3 682 (-5425 3700)(-5425 3975);
WIRE 16 2175 (-5575 4025)(-5025 4025);
WIRE 16 2175 (-5025 4025)(-5025 3600);
WIRE 16 2175 (-5575 4025)(-5575 3600);
WIRE 16 2175 (-5575 3600)(-5025 3600);
WIRE 3 2175 (-5925 4500)(-5525 4500);
WIRE 3 2175 (-5525 4500)(-5525 4200);
WIRE 3 2175 (-5925 4500)(-5925 4200);
WIRE 3 2175 (-5925 4200)(-5525 4200);
WIRE 16 682 (-2375 1025)(-3225 1025);
WIRE 16 682 (-2375 1750)(-2375 1025);
WIRE 16 682 (-3225 1025)(-3225 1750);
WIRE 16 682 (-3225 1750)(-2375 1750);
WIRE 16 -1 (-2500 3000)(-2500 3050);
WIRE 16 -1 (-2500 2950)(-2500 3000);
WIRE 16 -1 (-2500 3000)(-1900 3000);
FORCEPROP 2 LAST SIG_NAME VR_PVSA_CPU1_PHASE_SW_RC
J 0
(-2435 3010);
DISPLAY 0.617021 (-2435 3010);
PAINT ORANGE (-2435 3010);
FORCEPROP 2 LASTPROP $XRERR UNIQUE?
J 0
(-1870 3000);
DISPLAY 0.638298 (-1870 3000);
PAINT MONO (-1870 3000);
DISPLAY INVISIBLE (-1870 3000);
DOT 1 (-3100 3100);
DOT 1 (-1000 2900);
DOT 1 (-650 2900);
DOT 1 (-650 3300);
DOT 1 (-1000 3300);
DOT 1 (-1300 3300);
DOT 1 (-5200 4425);
DOT 1 (-1400 3300);
DOT 1 (-6375 4050);
DOT 1 (-4550 3950);
DOT 1 (-2500 3300);
DOT 1 (-6625 3575);
DOT 1 (-6625 4050);
DOT 1 (-6375 3575);
DOT 1 (-6700 4050);
DOT 1 (-3100 3150);
DOT 1 (-4825 4425);
DOT 1 (-4350 4050);
DOT 1 (-5600 1925);
DOT 1 (-5600 1475);
DOT 1 (-5950 1925);
DOT 1 (-5950 1475);
DOT 1 (-4450 3400);
DOT 1 (-2650 3800);
DOT 1 (-6125 4050);
DOT 1 (-6125 3575);
DOT 1 (-7175 3575);
DOT 1 (-6900 4050);
DOT 1 (-6900 3575);
DOT 1 (-5875 3575);
DOT 1 (-2500 3000);
DOT 1 (-3100 3050);
DOT 1 (-5475 3575);
DOT 1 (-5875 4150);
DOT 1 (-5475 4425);
DOT 1 (-1900 1600);
DOT 1 (-1900 1150);
FORCENOTE
SPOF
(-6130 2925) 0;
DISPLAY LEFT (-6130 2925);
DISPLAY 1.808511 (-6130 2925);
PAINT PURPLE (-6130 2925);
FORCENOTE
ROOM=PVSA_CPU1_PWR_VR
(-3180 1935) 0;
DISPLAY LEFT (-3180 1935);
DISPLAY 2.446809 (-3180 1935);
PAINT PURPLE (-3180 1935);
FORCENOTE
TP FAB1 CO-LAY WITH TI PARTS 11/16
(-5675 2875) 0;
DISPLAY LEFT (-5675 2875);
DISPLAY 0.851064 (-5675 2875);
PAINT RED (-5675 2875);
FORCENOTE
TDA21460
(-3875 4225) 0;
DISPLAY LEFT (-3875 4225);
DISPLAY 1.021277 (-3875 4225);
PAINT SKYBLUE (-3875 4225);
FORCENOTE
TP FAB1 ADD NET NAME 12/04
(-2575 2475) 0;
DISPLAY LEFT (-2575 2475);
DISPLAY 1.021277 (-2575 2475);
PAINT RED (-2575 2475);
FORCENOTE
TP FAB1 CHANGE RES TO 1 OHM 0603 0107
(-2575 2275) 0;
DISPLAY LEFT (-2575 2275);
DISPLAY 1.021277 (-2575 2275);
PAINT RED (-2575 2275);
FORCENOTE
ROOM = PVSA_CPU1_DECAP_VR
(-3240 615) 0;
DISPLAY LEFT (-3240 615);
DISPLAY 2.446809 (-3240 615);
PAINT PURPLE (-3240 615);
FORCENOTE
SOCKET SIDE
(-4465 1740) 0;
DISPLAY LEFT (-4465 1740);
PAINT PURPLE (-4465 1740);
FORCENOTE
ROUT AS DIFF PAIR
(-6565 1715) 0;
DISPLAY LEFT (-6565 1715);
DISPLAY 0.808511 (-6565 1715);
PAINT PURPLE (-6565 1715);
FORCENOTE
PVSA CPU0 VOLTAGE SENSE
(-7190 1365) 0;
DISPLAY LEFT (-7190 1365);
PAINT PURPLE (-7190 1365);
FORCENOTE
DC TOL = +/-5MV
(-3200 1425) 0;
DISPLAY LEFT (-3200 1425);
DISPLAY 0.808511 (-3200 1425);
PAINT PURPLE (-3200 1425);
FORCENOTE
RIPPLE = +/- 10MV
(-3200 1475) 0;
DISPLAY LEFT (-3200 1475);
DISPLAY 0.808511 (-3200 1475);
PAINT PURPLE (-3200 1475);
FORCENOTE
IOUT STEP=5A/US
(-3200 1225) 0;
DISPLAY LEFT (-3200 1225);
DISPLAY 0.808511 (-3200 1225);
PAINT PURPLE (-3200 1225);
FORCENOTE
VBOOT=0.9V
(-3200 1075) 0;
DISPLAY LEFT (-3200 1075);
DISPLAY 0.808511 (-3200 1075);
PAINT PURPLE (-3200 1075);
FORCENOTE
ROOM = PVSA_CPU1_VSENSE_VR
(-7065 715) 0;
DISPLAY LEFT (-7065 715);
DISPLAY 2.446809 (-7065 715);
PAINT PURPLE (-7065 715);
FORCENOTE
10MIL WIDTH
(-6440 1640) 0;
DISPLAY LEFT (-6440 1640);
DISPLAY 0.808511 (-6440 1640);
PAINT PURPLE (-6440 1640);
FORCENOTE
5MIL SPACING
(-6465 1565) 0;
DISPLAY LEFT (-6465 1565);
DISPLAY 0.808511 (-6465 1565);
PAINT PURPLE (-6465 1565);
FORCENOTE
VR CONTROLLER SIDE
(-7590 1740) 0;
DISPLAY LEFT (-7590 1740);
PAINT PURPLE (-7590 1740);
FORCENOTE
TP FAB1 DEL NET 0309
(-2975 3875) 0;
DISPLAY LEFT (-2975 3875);
DISPLAY 1.021277 (-2975 3875);
PAINT RED (-2975 3875);
FORCENOTE
SW FREQ=520 KHZ
(-3200 1125) 0;
DISPLAY LEFT (-3200 1125);
DISPLAY 0.808511 (-3200 1125);
PAINT PURPLE (-3200 1125);
FORCENOTE
IOUT DI/DT =20A/US
(-3200 1175) 0;
DISPLAY LEFT (-3200 1175);
DISPLAY 0.808511 (-3200 1175);
PAINT PURPLE (-3200 1175);
FORCENOTE
IOUT TDC=15A
(-3200 1325) 0;
DISPLAY LEFT (-3200 1325);
DISPLAY 0.808511 (-3200 1325);
PAINT PURPLE (-3200 1325);
FORCENOTE
IOUT PK=16A
(-3200 1275) 0;
DISPLAY LEFT (-3200 1275);
DISPLAY 0.808511 (-3200 1275);
PAINT PURPLE (-3200 1275);
FORCENOTE
TP FAB1 CO-LAY WITH TI PARTS 11/16
(-2200 3550) 0;
DISPLAY LEFT (-2200 3550);
DISPLAY 0.851064 (-2200 3550);
PAINT RED (-2200 3550);
FORCENOTE
TP FAB1 CHANGE PN 0310
(-5575 4050) 0;
DISPLAY LEFT (-5575 4050);
DISPLAY 1.021277 (-5575 4050);
PAINT RED (-5575 4050);
FORCENOTE
TP FAB1 CHANGE TO 0 OHM 0107
(-5975 4525) 0;
DISPLAY LEFT (-5975 4525);
DISPLAY 0.638298 (-5975 4525);
PAINT RED (-5975 4525);
FORCENOTE
TOTAL TOL = 0.917MAX/0.779VMIN 
(-3200 1375) 0;
DISPLAY LEFT (-3200 1375);
DISPLAY 0.808511 (-3200 1375);
PAINT PURPLE (-3200 1375);
FORCENOTE
TP FAB1 CHANGE L1C1 PN 0122
(-2050 3400) 0;
DISPLAY LEFT (-2050 3400);
DISPLAY 1.021277 (-2050 3400);
PAINT RED (-2050 3400);
FORCENOTE
VOUT=0.85V (TYP) SVID
(-3200 1525) 0;
DISPLAY LEFT (-3200 1525);
DISPLAY 0.808511 (-3200 1525);
PAINT PURPLE (-3200 1525);
FORCENOTE
PLACE ON TOP
(-5730 3500) 0;
DISPLAY LEFT (-5730 3500);
DISPLAY 1.553191 (-5730 3500);
PAINT PURPLE (-5730 3500);
FORCENOTE
TP FAB1 CO-LAY WITH TI PARTS 11/16
(-2575 2400) 0;
DISPLAY LEFT (-2575 2400);
DISPLAY 0.851064 (-2575 2400);
PAINT RED (-2575 2400);
QUIT
